FILE_TYPE = MACRO_DRAWING;
SET COLOR_WIRE YELLOW;
SET COLOR_PROP ORANGE;
SET COLOR_DOT WHITE;
SET COLOR_ARC YELLOW;
SET COLOR_BODY GREEN;
SET COLOR_NOTE PURPLE;
SET PROP_DISPLAY VALUE;
SET PAGE_NUMBER P246;
FORCEADD UNIVERSAL_GND..1
(-7175 2300);
FORCEPROP 3 LASTPIN (-7175 2350) SIG_NAME GND\g
J 0
(-7165 2360);
DISPLAY 0.659574 (-7165 2360);
PAINT MONO (-7165 2360);
DISPLAY INVISIBLE (-7165 2360);
FORCEPROP 2 LAST CDS_LIB pure_quanta_power
J 0
(-7175 2300);
PAINT MONO (-7175 2300);
DISPLAY INVISIBLE (-7175 2300);
FORCEPROP 1 LAST HDL_POWER GND
J 1
(-7150 2225);
DISPLAY 0.872340 (-7150 2225);
PAINT GREEN (-7150 2225);
DISPLAY INVISIBLE (-7150 2225);
FORCEPROP 1 LAST PATH I1
J 0
(-7100 2300);
DISPLAY 0.872340 (-7100 2300);
PAINT AQUA (-7100 2300);
DISPLAY INVISIBLE (-7100 2300);
FORCEADD OFFPAGE..1
(-4750 975);
FORCEPROP 2 LAST $XR0 123 
J 0
(-5002 975);
DISPLAY 0.638298 (-5002 975);
PAINT MONO (-5002 975);
FORCEPROP 2 LAST CDS_LIB standard
J 0
(-4750 975);
DISPLAY INVISIBLE (-4750 975);
FORCEPROP 1 LAST OFFPAGE TRUE
J 0
(-4425 850);
DISPLAY 0.872340 (-4425 850);
DISPLAY INVISIBLE (-4425 850);
FORCEPROP 1 LAST COMMENT_BODY TRUE
J 0
(-4625 875);
DISPLAY 1.170213 (-4625 875);
PAINT GREEN (-4625 875);
DISPLAY INVISIBLE (-4625 875);
FORCEPROP 2 LAST PATH I10
J 0
(-5000 1025);
DISPLAY 0.680851 (-5000 1025);
DISPLAY INVISIBLE (-5000 1025);
FORCEADD OFFPAGE..1
(-4750 875);
FORCEPROP 2 LAST $XR0 123 
J 0
(-5002 875);
DISPLAY 0.638298 (-5002 875);
PAINT MONO (-5002 875);
FORCEPROP 2 LAST CDS_LIB standard
J 0
(-4750 875);
DISPLAY INVISIBLE (-4750 875);
FORCEPROP 1 LAST OFFPAGE TRUE
J 0
(-4425 750);
DISPLAY 0.872340 (-4425 750);
DISPLAY INVISIBLE (-4425 750);
FORCEPROP 1 LAST COMMENT_BODY TRUE
J 0
(-4625 775);
DISPLAY 1.170213 (-4625 775);
PAINT GREEN (-4625 775);
DISPLAY INVISIBLE (-4625 775);
FORCEPROP 2 LAST PATH I11
J 0
(-5000 925);
DISPLAY 0.680851 (-5000 925);
DISPLAY INVISIBLE (-5000 925);
FORCEADD OFFPAGE..1
(-4750 1075);
FORCEPROP 2 LAST $XR1 81 
J 0
(-5092 1075);
DISPLAY 0.638298 (-5092 1075);
PAINT MONO (-5092 1075);
FORCEPROP 2 LAST $XR0 123 
J 0
(-5002 1075);
DISPLAY 0.638298 (-5002 1075);
PAINT MONO (-5002 1075);
FORCEPROP 2 LAST CDS_LIB standard
J 0
(-4750 1075);
DISPLAY INVISIBLE (-4750 1075);
FORCEPROP 1 LAST OFFPAGE TRUE
J 0
(-4425 950);
DISPLAY 0.872340 (-4425 950);
DISPLAY INVISIBLE (-4425 950);
FORCEPROP 1 LAST COMMENT_BODY TRUE
J 0
(-4625 975);
DISPLAY 1.170213 (-4625 975);
PAINT GREEN (-4625 975);
DISPLAY INVISIBLE (-4625 975);
FORCEPROP 2 LAST PATH I12
J 0
(-5000 1125);
DISPLAY 0.680851 (-5000 1125);
DISPLAY INVISIBLE (-5000 1125);
FORCEADD OFFPAGE..1
(-4750 1400);
FORCEPROP 2 LAST $XR1 81 
J 0
(-5092 1400);
DISPLAY 0.638298 (-5092 1400);
PAINT MONO (-5092 1400);
FORCEPROP 2 LAST $XR0 125 
J 0
(-5002 1400);
DISPLAY 0.638298 (-5002 1400);
PAINT MONO (-5002 1400);
FORCEPROP 2 LAST CDS_LIB standard
J 0
(-4750 1400);
DISPLAY INVISIBLE (-4750 1400);
FORCEPROP 1 LAST OFFPAGE TRUE
J 0
(-4425 1275);
DISPLAY 0.872340 (-4425 1275);
DISPLAY INVISIBLE (-4425 1275);
FORCEPROP 1 LAST COMMENT_BODY TRUE
J 0
(-4625 1300);
DISPLAY 1.170213 (-4625 1300);
PAINT GREEN (-4625 1300);
DISPLAY INVISIBLE (-4625 1300);
FORCEPROP 2 LAST PATH I13
J 0
(-5000 1450);
DISPLAY 0.680851 (-5000 1450);
DISPLAY INVISIBLE (-5000 1450);
FORCEADD OFFPAGE..1
(-4750 1500);
FORCEPROP 2 LAST $XR1 81 
J 0
(-5092 1500);
DISPLAY 0.638298 (-5092 1500);
PAINT MONO (-5092 1500);
FORCEPROP 2 LAST $XR0 125 
J 0
(-5002 1500);
DISPLAY 0.638298 (-5002 1500);
PAINT MONO (-5002 1500);
FORCEPROP 2 LAST CDS_LIB standard
J 0
(-4750 1500);
DISPLAY INVISIBLE (-4750 1500);
FORCEPROP 1 LAST OFFPAGE TRUE
J 0
(-4425 1375);
DISPLAY 0.872340 (-4425 1375);
DISPLAY INVISIBLE (-4425 1375);
FORCEPROP 1 LAST COMMENT_BODY TRUE
J 0
(-4625 1400);
DISPLAY 1.170213 (-4625 1400);
PAINT GREEN (-4625 1400);
DISPLAY INVISIBLE (-4625 1400);
FORCEPROP 2 LAST PATH I14
J 0
(-5000 1550);
DISPLAY 0.680851 (-5000 1550);
DISPLAY INVISIBLE (-5000 1550);
FORCEADD OFFPAGE..1
(-4750 1700);
FORCEPROP 2 LAST $XR1 80 
J 0
(-5092 1700);
DISPLAY 0.638298 (-5092 1700);
PAINT MONO (-5092 1700);
FORCEPROP 2 LAST $XR0 125 
J 0
(-5002 1700);
DISPLAY 0.638298 (-5002 1700);
PAINT MONO (-5002 1700);
FORCEPROP 2 LAST CDS_LIB standard
J 0
(-4750 1700);
DISPLAY INVISIBLE (-4750 1700);
FORCEPROP 1 LAST OFFPAGE TRUE
J 0
(-4425 1575);
DISPLAY 0.872340 (-4425 1575);
DISPLAY INVISIBLE (-4425 1575);
FORCEPROP 1 LAST COMMENT_BODY TRUE
J 0
(-4625 1600);
DISPLAY 1.170213 (-4625 1600);
PAINT GREEN (-4625 1600);
DISPLAY INVISIBLE (-4625 1600);
FORCEPROP 2 LAST PATH I15
J 0
(-5000 1750);
DISPLAY 0.680851 (-5000 1750);
DISPLAY INVISIBLE (-5000 1750);
FORCEADD OFFPAGE..1
(-4750 1600);
FORCEPROP 2 LAST $XR0 123 
J 0
(-5002 1600);
DISPLAY 0.638298 (-5002 1600);
PAINT MONO (-5002 1600);
FORCEPROP 2 LAST CDS_LIB standard
J 0
(-4750 1600);
DISPLAY INVISIBLE (-4750 1600);
FORCEPROP 1 LAST OFFPAGE TRUE
J 0
(-4425 1475);
DISPLAY 0.872340 (-4425 1475);
DISPLAY INVISIBLE (-4425 1475);
FORCEPROP 1 LAST COMMENT_BODY TRUE
J 0
(-4625 1500);
DISPLAY 1.170213 (-4625 1500);
PAINT GREEN (-4625 1500);
DISPLAY INVISIBLE (-4625 1500);
FORCEPROP 2 LAST PATH I16
J 0
(-5000 1650);
DISPLAY 0.680851 (-5000 1650);
DISPLAY INVISIBLE (-5000 1650);
FORCEADD OFFPAGE..1
(-4750 1825);
FORCEPROP 2 LAST $XR1 81 
J 0
(-5092 1825);
DISPLAY 0.638298 (-5092 1825);
PAINT MONO (-5092 1825);
FORCEPROP 2 LAST $XR0 126 
J 0
(-5002 1825);
DISPLAY 0.638298 (-5002 1825);
PAINT MONO (-5002 1825);
FORCEPROP 2 LAST CDS_LIB standard
J 0
(-4750 1825);
DISPLAY INVISIBLE (-4750 1825);
FORCEPROP 1 LAST OFFPAGE TRUE
J 0
(-4425 1700);
DISPLAY 0.872340 (-4425 1700);
DISPLAY INVISIBLE (-4425 1700);
FORCEPROP 1 LAST COMMENT_BODY TRUE
J 0
(-4625 1725);
DISPLAY 1.170213 (-4625 1725);
PAINT GREEN (-4625 1725);
DISPLAY INVISIBLE (-4625 1725);
FORCEPROP 2 LAST PATH I17
J 0
(-5000 1875);
DISPLAY 0.680851 (-5000 1875);
DISPLAY INVISIBLE (-5000 1875);
FORCEADD OFFPAGE..1
(-4750 2250);
FORCEPROP 2 LAST $XR1 123 
J 0
(-5122 2250);
DISPLAY 0.638298 (-5122 2250);
PAINT MONO (-5122 2250);
FORCEPROP 2 LAST $XR0 121 
J 0
(-5002 2250);
DISPLAY 0.638298 (-5002 2250);
PAINT MONO (-5002 2250);
FORCEPROP 2 LAST CDS_LIB standard
J 0
(-4750 2250);
DISPLAY INVISIBLE (-4750 2250);
FORCEPROP 1 LAST OFFPAGE TRUE
J 0
(-4425 2125);
DISPLAY 0.872340 (-4425 2125);
DISPLAY INVISIBLE (-4425 2125);
FORCEPROP 1 LAST COMMENT_BODY TRUE
J 0
(-4625 2150);
DISPLAY 1.170213 (-4625 2150);
PAINT GREEN (-4625 2150);
DISPLAY INVISIBLE (-4625 2150);
FORCEPROP 2 LAST PATH I18
J 0
(-5000 2300);
DISPLAY 0.680851 (-5000 2300);
DISPLAY INVISIBLE (-5000 2300);
FORCEADD OFFPAGE..1
(-4750 2450);
FORCEPROP 2 LAST $XR1 123 
J 0
(-5122 2450);
DISPLAY 0.638298 (-5122 2450);
PAINT MONO (-5122 2450);
FORCEPROP 2 LAST $XR0 121 
J 0
(-5002 2450);
DISPLAY 0.638298 (-5002 2450);
PAINT MONO (-5002 2450);
FORCEPROP 2 LAST CDS_LIB standard
J 0
(-4750 2450);
DISPLAY INVISIBLE (-4750 2450);
FORCEPROP 1 LAST OFFPAGE TRUE
J 0
(-4425 2325);
DISPLAY 0.872340 (-4425 2325);
DISPLAY INVISIBLE (-4425 2325);
FORCEPROP 1 LAST COMMENT_BODY TRUE
J 0
(-4625 2350);
DISPLAY 1.170213 (-4625 2350);
PAINT GREEN (-4625 2350);
DISPLAY INVISIBLE (-4625 2350);
FORCEPROP 2 LAST PATH I19
J 0
(-5000 2500);
DISPLAY 0.680851 (-5000 2500);
DISPLAY INVISIBLE (-5000 2500);
FORCEADD Q_RES..2
(-7175 2525);
FORCEPROP 1 LAST LOCATION R2694
J 0
(-7130 2650);
DISPLAY 0.638298 (-7130 2650);
FORCEPROP 0 LAST $SEC 1
J 0
(-7125 2700);
DISPLAY 0.680851 (-7125 2700);
PAINT MONO (-7125 2700);
DISPLAY INVISIBLE (-7125 2700);
FORCEPROP 0 LAST CDS_SEC 1
J 0
(-7125 2700);
DISPLAY 1.021277 (-7125 2700);
DISPLAY INVISIBLE (-7125 2700);
FORCEPROP 1 LASTPIN (-7175 2625) $PN 1
J 0
(-7170 2587);
DISPLAY 0.787234 (-7170 2587);
PAINT MONO (-7170 2587);
FORCEPROP 1 LASTPIN (-7175 2425) $PN 2
J 0
(-7170 2435);
DISPLAY 0.787234 (-7170 2435);
PAINT MONO (-7170 2435);
FORCEPROP 1 LAST MATERIAL CHIP
J 0
(-7135 2450);
DISPLAY 0.638298 (-7135 2450);
FORCEPROP 1 LAST VALUE 1K
J 0
(-7130 2600);
DISPLAY 0.638298 (-7130 2600);
FORCEPROP 1 LAST TOLERANCE 1%
J 0
(-7130 2550);
DISPLAY 0.638298 (-7130 2550);
FORCEPROP 1 LAST WATTAGE 1/16W
J 0
(-7135 2500);
DISPLAY 0.638298 (-7135 2500);
FORCEPROP 1 LAST PACK_TYPE 0402LF
J 0
(-7135 2400);
DISPLAY 0.638298 (-7135 2400);
FORCEPROP 2 LAST CDS_LIB pure_quanta
J 0
(-7175 2525);
DISPLAY INVISIBLE (-7175 2525);
FORCEPROP 1 LAST PATH I2
J 0
(-7125 2700);
DISPLAY 0.978723 (-7125 2700);
PAINT WHITE (-7125 2700);
DISPLAY INVISIBLE (-7125 2700);
FORCEPROP 1 LAST PART_NUMBER CS21002FB06
J 0
(-7135 2350);
DISPLAY 0.638298 (-7135 2350);
DISPLAY INVISIBLE (-7135 2350);
FORCEADD OFFPAGE..1
(-4750 2650);
FORCEPROP 2 LAST $XR1 123 
J 0
(-5122 2650);
DISPLAY 0.638298 (-5122 2650);
PAINT MONO (-5122 2650);
FORCEPROP 2 LAST $XR0 121 
J 0
(-5002 2650);
DISPLAY 0.638298 (-5002 2650);
PAINT MONO (-5002 2650);
FORCEPROP 2 LAST CDS_LIB standard
J 0
(-4750 2650);
DISPLAY INVISIBLE (-4750 2650);
FORCEPROP 1 LAST OFFPAGE TRUE
J 0
(-4425 2525);
DISPLAY 0.872340 (-4425 2525);
DISPLAY INVISIBLE (-4425 2525);
FORCEPROP 1 LAST COMMENT_BODY TRUE
J 0
(-4625 2550);
DISPLAY 1.170213 (-4625 2550);
PAINT GREEN (-4625 2550);
DISPLAY INVISIBLE (-4625 2550);
FORCEPROP 2 LAST PATH I20
J 0
(-5000 2700);
DISPLAY 0.680851 (-5000 2700);
DISPLAY INVISIBLE (-5000 2700);
FORCEADD OFFPAGE..1
(-4750 2850);
FORCEPROP 2 LAST $XR1 123 
J 0
(-5122 2850);
DISPLAY 0.638298 (-5122 2850);
PAINT MONO (-5122 2850);
FORCEPROP 2 LAST $XR0 121 
J 0
(-5002 2850);
DISPLAY 0.638298 (-5002 2850);
PAINT MONO (-5002 2850);
FORCEPROP 2 LAST CDS_LIB standard
J 0
(-4750 2850);
DISPLAY INVISIBLE (-4750 2850);
FORCEPROP 1 LAST OFFPAGE TRUE
J 0
(-4425 2725);
DISPLAY 0.872340 (-4425 2725);
DISPLAY INVISIBLE (-4425 2725);
FORCEPROP 1 LAST COMMENT_BODY TRUE
J 0
(-4625 2750);
DISPLAY 1.170213 (-4625 2750);
PAINT GREEN (-4625 2750);
DISPLAY INVISIBLE (-4625 2750);
FORCEPROP 2 LAST PATH I21
J 0
(-5000 2900);
DISPLAY 0.680851 (-5000 2900);
DISPLAY INVISIBLE (-5000 2900);
FORCEADD OFFPAGE..1
(-4750 3050);
FORCEPROP 2 LAST $XR0 251 
J 0
(-5002 3050);
DISPLAY 0.638298 (-5002 3050);
PAINT MONO (-5002 3050);
FORCEPROP 2 LAST CDS_LIB standard
J 0
(-4750 3050);
DISPLAY INVISIBLE (-4750 3050);
FORCEPROP 1 LAST OFFPAGE TRUE
J 0
(-4425 2925);
DISPLAY 0.872340 (-4425 2925);
DISPLAY INVISIBLE (-4425 2925);
FORCEPROP 1 LAST COMMENT_BODY TRUE
J 0
(-4625 2950);
DISPLAY 1.170213 (-4625 2950);
PAINT GREEN (-4625 2950);
DISPLAY INVISIBLE (-4625 2950);
FORCEPROP 2 LAST PATH I22
J 0
(-5000 3100);
DISPLAY 0.680851 (-5000 3100);
DISPLAY INVISIBLE (-5000 3100);
FORCEADD OFFPAGE..1
(-4750 3250);
FORCEPROP 2 LAST $XR0 251 
J 0
(-5002 3250);
DISPLAY 0.638298 (-5002 3250);
PAINT MONO (-5002 3250);
FORCEPROP 2 LAST CDS_LIB standard
J 0
(-4750 3250);
DISPLAY INVISIBLE (-4750 3250);
FORCEPROP 1 LAST OFFPAGE TRUE
J 0
(-4425 3125);
DISPLAY 0.872340 (-4425 3125);
DISPLAY INVISIBLE (-4425 3125);
FORCEPROP 1 LAST COMMENT_BODY TRUE
J 0
(-4625 3150);
DISPLAY 1.170213 (-4625 3150);
PAINT GREEN (-4625 3150);
DISPLAY INVISIBLE (-4625 3150);
FORCEPROP 2 LAST PATH I23
J 0
(-5000 3300);
DISPLAY 0.680851 (-5000 3300);
DISPLAY INVISIBLE (-5000 3300);
FORCEADD OFFPAGE..1
(-4750 3475);
FORCEPROP 2 LAST $XR0 246 
J 0
(-5002 3475);
DISPLAY 0.638298 (-5002 3475);
PAINT MONO (-5002 3475);
FORCEPROP 2 LAST CDS_LIB standard
J 0
(-4750 3475);
DISPLAY INVISIBLE (-4750 3475);
FORCEPROP 1 LAST OFFPAGE TRUE
J 0
(-4425 3350);
DISPLAY 0.872340 (-4425 3350);
DISPLAY INVISIBLE (-4425 3350);
FORCEPROP 1 LAST COMMENT_BODY TRUE
J 0
(-4625 3375);
DISPLAY 1.170213 (-4625 3375);
PAINT GREEN (-4625 3375);
DISPLAY INVISIBLE (-4625 3375);
FORCEPROP 2 LAST PATH I24
J 0
(-5000 3525);
DISPLAY 0.680851 (-5000 3525);
DISPLAY INVISIBLE (-5000 3525);
FORCEADD UNIVERSAL_GND..1
(-4950 4175);
FORCEPROP 3 LASTPIN (-4950 4225) SIG_NAME GND\g
J 0
(-4940 4235);
DISPLAY 0.659574 (-4940 4235);
PAINT MONO (-4940 4235);
DISPLAY INVISIBLE (-4940 4235);
FORCEPROP 2 LAST CDS_LIB pure_quanta_power
J 0
(-4950 4175);
PAINT MONO (-4950 4175);
DISPLAY INVISIBLE (-4950 4175);
FORCEPROP 1 LAST HDL_POWER GND
J 1
(-4925 4100);
DISPLAY 0.872340 (-4925 4100);
PAINT GREEN (-4925 4100);
DISPLAY INVISIBLE (-4925 4100);
FORCEPROP 1 LAST PATH I25
J 0
(-4875 4175);
DISPLAY 0.872340 (-4875 4175);
PAINT AQUA (-4875 4175);
DISPLAY INVISIBLE (-4875 4175);
FORCEADD OFFPAGE..1
(-7200 5300);
FORCEPROP 2 LAST $XR5 253 
J 0
(-8021 5300);
DISPLAY 0.638298 (-8021 5300);
PAINT MONO (-8021 5300);
FORCEPROP 2 LAST $XR4 251 
J 0
(-7901 5300);
DISPLAY 0.638298 (-7901 5300);
PAINT MONO (-7901 5300);
FORCEPROP 2 LAST $XR3 241 
J 0
(-7781 5300);
DISPLAY 0.638298 (-7781 5300);
PAINT MONO (-7781 5300);
FORCEPROP 2 LAST $XR2 139 
J 0
(-7661 5300);
DISPLAY 0.638298 (-7661 5300);
PAINT MONO (-7661 5300);
FORCEPROP 2 LAST $XR1 132 
J 0
(-7541 5300);
DISPLAY 0.638298 (-7541 5300);
PAINT MONO (-7541 5300);
FORCEPROP 2 LAST $XR0 80 
J 0
(-7421 5300);
DISPLAY 0.638298 (-7421 5300);
PAINT MONO (-7421 5300);
FORCEPROP 2 LAST CDS_LIB standard
J 0
(-7200 5300);
DISPLAY INVISIBLE (-7200 5300);
FORCEPROP 1 LAST OFFPAGE TRUE
J 0
(-6875 5175);
DISPLAY 0.872340 (-6875 5175);
DISPLAY INVISIBLE (-6875 5175);
FORCEPROP 1 LAST COMMENT_BODY TRUE
J 0
(-7075 5200);
DISPLAY 0.872340 (-7075 5200);
PAINT GREEN (-7075 5200);
DISPLAY INVISIBLE (-7075 5200);
FORCEPROP 2 LAST PATH I26
J 0
(-7400 5350);
DISPLAY 0.680851 (-7400 5350);
DISPLAY INVISIBLE (-7400 5350);
FORCEADD OFFPAGE..1
(-5975 4500);
FORCEPROP 2 LAST $XR0 246 
J 0
(-6227 4500);
DISPLAY 0.638298 (-6227 4500);
PAINT MONO (-6227 4500);
FORCEPROP 2 LAST CDS_LIB standard
J 0
(-5975 4500);
DISPLAY INVISIBLE (-5975 4500);
FORCEPROP 1 LAST OFFPAGE TRUE
J 0
(-5650 4375);
DISPLAY 0.872340 (-5650 4375);
DISPLAY INVISIBLE (-5650 4375);
FORCEPROP 1 LAST COMMENT_BODY TRUE
J 0
(-5850 4400);
DISPLAY 1.170213 (-5850 4400);
PAINT GREEN (-5850 4400);
DISPLAY INVISIBLE (-5850 4400);
FORCEPROP 2 LAST PATH I27
J 0
(-6225 4550);
DISPLAY 0.680851 (-6225 4550);
DISPLAY INVISIBLE (-6225 4550);
FORCEADD OFFPAGE..1
(-5975 4600);
FORCEPROP 2 LAST $XR0 246 
J 0
(-6227 4600);
DISPLAY 0.638298 (-6227 4600);
PAINT MONO (-6227 4600);
FORCEPROP 2 LAST CDS_LIB standard
J 0
(-5975 4600);
DISPLAY INVISIBLE (-5975 4600);
FORCEPROP 1 LAST OFFPAGE TRUE
J 0
(-5650 4475);
DISPLAY 0.872340 (-5650 4475);
DISPLAY INVISIBLE (-5650 4475);
FORCEPROP 1 LAST COMMENT_BODY TRUE
J 0
(-5850 4500);
DISPLAY 1.170213 (-5850 4500);
PAINT GREEN (-5850 4500);
DISPLAY INVISIBLE (-5850 4500);
FORCEPROP 2 LAST PATH I28
J 0
(-6225 4650);
DISPLAY 0.680851 (-6225 4650);
DISPLAY INVISIBLE (-6225 4650);
FORCEADD OFFPAGE..1
(-5975 4700);
FORCEPROP 2 LAST $XR0 246 
J 0
(-6227 4700);
DISPLAY 0.638298 (-6227 4700);
PAINT MONO (-6227 4700);
FORCEPROP 2 LAST CDS_LIB standard
J 0
(-5975 4700);
DISPLAY INVISIBLE (-5975 4700);
FORCEPROP 1 LAST OFFPAGE TRUE
J 0
(-5650 4575);
DISPLAY 0.872340 (-5650 4575);
DISPLAY INVISIBLE (-5650 4575);
FORCEPROP 1 LAST COMMENT_BODY TRUE
J 0
(-5850 4600);
DISPLAY 1.170213 (-5850 4600);
PAINT GREEN (-5850 4600);
DISPLAY INVISIBLE (-5850 4600);
FORCEPROP 2 LAST PATH I29
J 0
(-6225 4750);
DISPLAY 0.680851 (-6225 4750);
DISPLAY INVISIBLE (-6225 4750);
FORCEADD Q_RES..2
(-7175 3125);
FORCEPROP 1 LAST LOCATION R2693
J 0
(-7130 3250);
DISPLAY 0.638298 (-7130 3250);
FORCEPROP 0 LAST $SEC 1
J 0
(-7125 3300);
DISPLAY 0.680851 (-7125 3300);
PAINT MONO (-7125 3300);
DISPLAY INVISIBLE (-7125 3300);
FORCEPROP 0 LAST CDS_SEC 1
J 0
(-7125 3300);
DISPLAY 1.021277 (-7125 3300);
DISPLAY INVISIBLE (-7125 3300);
FORCEPROP 1 LASTPIN (-7175 3225) $PN 1
J 0
(-7170 3187);
DISPLAY 0.787234 (-7170 3187);
PAINT MONO (-7170 3187);
FORCEPROP 1 LASTPIN (-7175 3025) $PN 2
J 0
(-7170 3035);
DISPLAY 0.787234 (-7170 3035);
PAINT MONO (-7170 3035);
FORCEPROP 1 LAST TOLERANCE 1%
J 0
(-7130 3150);
DISPLAY 0.638298 (-7130 3150);
FORCEPROP 1 LAST WATTAGE 1/16W
J 0
(-7135 3100);
DISPLAY 0.638298 (-7135 3100);
FORCEPROP 1 LAST VALUE 1K
J 0
(-7130 3200);
DISPLAY 0.638298 (-7130 3200);
FORCEPROP 1 LAST MATERIAL EMPTY
J 0
(-7135 3050);
DISPLAY 0.638298 (-7135 3050);
PAINT RED (-7135 3050);
FORCEPROP 1 LAST PACK_TYPE 0402LF
J 0
(-7135 3000);
DISPLAY 0.638298 (-7135 3000);
FORCEPROP 2 LAST CDS_LIB pure_quanta
J 0
(-7175 3125);
DISPLAY INVISIBLE (-7175 3125);
FORCEPROP 1 LAST PATH I3
J 0
(-7125 3300);
DISPLAY 0.978723 (-7125 3300);
PAINT WHITE (-7125 3300);
DISPLAY INVISIBLE (-7125 3300);
FORCEPROP 1 LAST PART_NUMBER CS21002FB06
J 0
(-7135 2950);
DISPLAY 0.638298 (-7135 2950);
DISPLAY INVISIBLE (-7135 2950);
FORCEADD OFFPAGE..1
(-5975 4800);
FORCEPROP 2 LAST $XR0 246 
J 0
(-6227 4800);
DISPLAY 0.638298 (-6227 4800);
PAINT MONO (-6227 4800);
FORCEPROP 2 LAST CDS_LIB standard
J 0
(-5975 4800);
DISPLAY INVISIBLE (-5975 4800);
FORCEPROP 1 LAST OFFPAGE TRUE
J 0
(-5650 4675);
DISPLAY 0.872340 (-5650 4675);
DISPLAY INVISIBLE (-5650 4675);
FORCEPROP 1 LAST COMMENT_BODY TRUE
J 0
(-5850 4700);
DISPLAY 1.170213 (-5850 4700);
PAINT GREEN (-5850 4700);
DISPLAY INVISIBLE (-5850 4700);
FORCEPROP 2 LAST PATH I30
J 0
(-6225 4850);
DISPLAY 0.680851 (-6225 4850);
DISPLAY INVISIBLE (-6225 4850);
FORCEADD Q_RES..1
(-6275 5300);
FORCEPROP 1 LAST LOCATION R2922
J 0
(-6500 5300);
DISPLAY 0.638298 (-6500 5300);
FORCEPROP 0 LAST $SEC 1
J 0
(-6500 5350);
DISPLAY 0.680851 (-6500 5350);
PAINT MONO (-6500 5350);
DISPLAY INVISIBLE (-6500 5350);
FORCEPROP 0 LAST CDS_SEC 1
J 0
(-6500 5350);
DISPLAY 1.021277 (-6500 5350);
DISPLAY INVISIBLE (-6500 5350);
FORCEPROP 1 LASTPIN (-6375 5300) $PN 1
J 0
(-6363 5312);
DISPLAY 0.787234 (-6363 5312);
PAINT MONO (-6363 5312);
FORCEPROP 1 LASTPIN (-6175 5300) $PN 2
J 0
(-6213 5312);
DISPLAY 0.787234 (-6213 5312);
PAINT MONO (-6213 5312);
FORCEPROP 1 LAST MATERIAL CHIP
J 0
(-6025 5300);
DISPLAY 0.510638 (-6025 5300);
FORCEPROP 1 LAST TOLERANCE 5%
J 0
(-6100 5300);
DISPLAY 0.510638 (-6100 5300);
FORCEPROP 1 LAST VALUE 0
J 2
(-6125 5300);
DISPLAY 0.510638 (-6125 5300);
FORCEPROP 2 LAST CDS_LIB pure_quanta
J 0
(-6275 5300);
DISPLAY INVISIBLE (-6275 5300);
FORCEPROP 1 LAST WATTAGE 1/16W
J 2
(-6175 5225);
DISPLAY 0.319149 (-6175 5225);
DISPLAY INVISIBLE (-6175 5225);
FORCEPROP 1 LAST PACK_TYPE 0402LF
J 0
(-6025 5300);
DISPLAY 0.510638 (-6025 5300);
DISPLAY INVISIBLE (-6025 5300);
FORCEPROP 1 LAST PATH I31
J 0
(-6325 5450);
DISPLAY 0.978723 (-6325 5450);
PAINT WHITE (-6325 5450);
DISPLAY INVISIBLE (-6325 5450);
FORCEPROP 1 LAST PART_NUMBER CS00002JB13
J 0
(-6350 5250);
DISPLAY 0.319149 (-6350 5250);
DISPLAY INVISIBLE (-6350 5250);
FORCEADD OFFPAGE..2
R 2
(-5975 5100);
FORCEPROP 2 LAST $XR0 246 
J 0
(-6230 5100);
DISPLAY 0.638298 (-6230 5100);
PAINT MONO (-6230 5100);
FORCEPROP 2 LAST CDS_LIB standard
J 2
(-5975 5100);
DISPLAY INVISIBLE (-5975 5100);
FORCEPROP 1 LAST OFFPAGE TRUE
J 2
(-6300 4975);
DISPLAY 0.872340 (-6300 4975);
DISPLAY INVISIBLE (-6300 4975);
FORCEPROP 1 LAST COMMENT_BODY TRUE
J 2
(-5930 5005);
DISPLAY 0.872340 (-5930 5005);
PAINT GREEN (-5930 5005);
DISPLAY INVISIBLE (-5930 5005);
FORCEPROP 2 LAST PATH I32
J 0
(-6250 5150);
DISPLAY 0.680851 (-6250 5150);
DISPLAY INVISIBLE (-6250 5150);
FORCEADD OFFPAGE..2
R 2
(-5975 5200);
FORCEPROP 2 LAST $XR2 235 
J 0
(-6470 5200);
DISPLAY 0.638298 (-6470 5200);
PAINT MONO (-6470 5200);
FORCEPROP 2 LAST $XR1 178 
J 0
(-6350 5200);
DISPLAY 0.638298 (-6350 5200);
PAINT MONO (-6350 5200);
FORCEPROP 2 LAST $XR0 176 
J 0
(-6230 5200);
DISPLAY 0.638298 (-6230 5200);
PAINT MONO (-6230 5200);
FORCEPROP 2 LAST CDS_LIB standard
J 2
(-5975 5200);
DISPLAY INVISIBLE (-5975 5200);
FORCEPROP 1 LAST OFFPAGE TRUE
J 2
(-6300 5075);
DISPLAY 0.872340 (-6300 5075);
DISPLAY INVISIBLE (-6300 5075);
FORCEPROP 1 LAST COMMENT_BODY TRUE
J 2
(-5930 5105);
DISPLAY 0.872340 (-5930 5105);
PAINT GREEN (-5930 5105);
DISPLAY INVISIBLE (-5930 5105);
FORCEPROP 2 LAST PATH I33
J 0
(-6250 5250);
DISPLAY 0.680851 (-6250 5250);
DISPLAY INVISIBLE (-6250 5250);
FORCEADD UNIVERSAL_POWER..1
(-6575 5925);
FORCEPROP 3 LASTPIN (-6575 5875) SIG_NAME P3V3_AUX\g
J 0
(-6565 5885);
DISPLAY 0.659574 (-6565 5885);
PAINT MONO (-6565 5885);
DISPLAY INVISIBLE (-6565 5885);
FORCEPROP 1 LAST HDL_POWER P3V3_AUX
J 1
(-6575 5975);
DISPLAY 0.872340 (-6575 5975);
PAINT GREEN (-6575 5975);
FORCEPROP 2 LAST CDS_LIB pure_quanta_power
J 0
(-6575 5925);
DISPLAY INVISIBLE (-6575 5925);
FORCEPROP 1 LAST PATH I34
J 0
(-6525 5950);
DISPLAY 0.872340 (-6525 5950);
PAINT AQUA (-6525 5950);
DISPLAY INVISIBLE (-6525 5950);
FORCEADD Q_RES..2
R 2
(-6575 5650);
FORCEPROP 1 LAST LOCATION R2921
J 2
(-6620 5775);
DISPLAY 0.978723 (-6620 5775);
FORCEPROP 2 LAST $SEC 1
J 0
(-6625 5875);
DISPLAY 0.680851 (-6625 5875);
PAINT MONO (-6625 5875);
DISPLAY INVISIBLE (-6625 5875);
FORCEPROP 2 LAST CDS_SEC 1
J 0
(-6625 5875);
DISPLAY 1.021277 (-6625 5875);
DISPLAY INVISIBLE (-6625 5875);
FORCEPROP 1 LASTPIN (-6575 5750) $PN 1
J 2
(-6580 5712);
DISPLAY 0.787234 (-6580 5712);
FORCEPROP 1 LASTPIN (-6575 5550) $PN 2
J 2
(-6580 5560);
DISPLAY 0.787234 (-6580 5560);
FORCEPROP 1 LAST WATTAGE 1/16W
J 2
(-6615 5625);
DISPLAY 0.638298 (-6615 5625);
FORCEPROP 1 LAST MATERIAL EMPTY
J 2
(-6615 5575);
DISPLAY 0.638298 (-6615 5575);
PAINT RED (-6615 5575);
FORCEPROP 1 LAST VALUE 10K
J 2
(-6620 5725);
DISPLAY 0.638298 (-6620 5725);
FORCEPROP 1 LAST TOLERANCE 1%
J 2
(-6620 5675);
DISPLAY 0.638298 (-6620 5675);
FORCEPROP 1 LAST PACK_TYPE 0402LF
J 2
(-6615 5525);
DISPLAY 0.638298 (-6615 5525);
FORCEPROP 2 LAST CDS_LIB pure_quanta
J 2
(-6575 5650);
PAINT MONO (-6575 5650);
DISPLAY INVISIBLE (-6575 5650);
FORCEPROP 1 LAST PATH I35
J 2
(-6625 5825);
DISPLAY 0.978723 (-6625 5825);
PAINT WHITE (-6625 5825);
DISPLAY INVISIBLE (-6625 5825);
FORCEPROP 1 LAST PART_NUMBER CS31002FB08
J 2
(-6615 5475);
DISPLAY 0.638298 (-6615 5475);
DISPLAY INVISIBLE (-6615 5475);
FORCEADD OFFPAGE..1
(-5975 5400);
FORCEPROP 2 LAST $XR0 246 
J 0
(-6227 5400);
DISPLAY 0.638298 (-6227 5400);
PAINT MONO (-6227 5400);
FORCEPROP 2 LAST CDS_LIB standard
J 2
(-5975 5400);
DISPLAY INVISIBLE (-5975 5400);
FORCEPROP 1 LAST OFFPAGE TRUE
J 0
(-5650 5275);
DISPLAY 0.872340 (-5650 5275);
PAINT GREEN (-5650 5275);
DISPLAY INVISIBLE (-5650 5275);
FORCEPROP 1 LAST COMMENT_BODY TRUE
J 0
(-5850 5300);
DISPLAY 0.872340 (-5850 5300);
PAINT GREEN (-5850 5300);
DISPLAY INVISIBLE (-5850 5300);
FORCEPROP 2 LAST PATH I36
J 0
(-6225 5450);
DISPLAY 0.680851 (-6225 5450);
DISPLAY INVISIBLE (-6225 5450);
FORCEADD Q_RES..2
(-5600 5800);
FORCEPROP 1 LAST LOCATION R2923
J 0
(-5555 5925);
DISPLAY 0.978723 (-5555 5925);
FORCEPROP 0 LAST $SEC 1
J 0
(-5550 5975);
DISPLAY 0.680851 (-5550 5975);
PAINT MONO (-5550 5975);
DISPLAY INVISIBLE (-5550 5975);
FORCEPROP 0 LAST CDS_SEC 1
J 0
(-5550 5975);
DISPLAY 1.021277 (-5550 5975);
DISPLAY INVISIBLE (-5550 5975);
FORCEPROP 1 LASTPIN (-5600 5900) $PN 1
J 0
(-5595 5862);
DISPLAY 0.787234 (-5595 5862);
PAINT MONO (-5595 5862);
FORCEPROP 1 LASTPIN (-5600 5700) $PN 2
J 0
(-5595 5710);
DISPLAY 0.787234 (-5595 5710);
PAINT MONO (-5595 5710);
FORCEPROP 1 LAST TOLERANCE 5%
J 0
(-5555 5825);
DISPLAY 0.510638 (-5555 5825);
FORCEPROP 1 LAST WATTAGE 1/16W
J 0
(-5560 5775);
DISPLAY 0.510638 (-5560 5775);
FORCEPROP 1 LAST VALUE 4.7K
J 0
(-5555 5875);
DISPLAY 0.510638 (-5555 5875);
FORCEPROP 1 LAST MATERIAL EMPTY
J 0
(-5560 5725);
DISPLAY 0.510638 (-5560 5725);
FORCEPROP 1 LAST PACK_TYPE 0402LF
J 0
(-5560 5625);
DISPLAY 0.510638 (-5560 5625);
FORCEPROP 2 LAST CDS_LIB pure_quanta
J 0
(-5600 5800);
DISPLAY INVISIBLE (-5600 5800);
FORCEPROP 1 LAST PATH I37
J 0
(-5550 5975);
DISPLAY 0.978723 (-5550 5975);
PAINT WHITE (-5550 5975);
DISPLAY INVISIBLE (-5550 5975);
FORCEPROP 1 LAST PART_NUMBER CS24702JB10
J 0
(-5560 5675);
DISPLAY 0.510638 (-5560 5675);
DISPLAY INVISIBLE (-5560 5675);
FORCEADD UNIVERSAL_POWER..1
(-5600 6025);
FORCEPROP 3 LASTPIN (-5600 5975) SIG_NAME P3V3_AUX\g
J 0
(-5590 5985);
DISPLAY 0.659574 (-5590 5985);
PAINT MONO (-5590 5985);
DISPLAY INVISIBLE (-5590 5985);
FORCEPROP 1 LAST HDL_POWER P3V3_AUX
J 1
(-5600 6075);
DISPLAY 0.872340 (-5600 6075);
PAINT GREEN (-5600 6075);
FORCEPROP 2 LAST CDS_LIB pure_quanta_power
J 0
(-5600 6025);
DISPLAY INVISIBLE (-5600 6025);
FORCEPROP 1 LAST PATH I38
J 0
(-5550 6050);
DISPLAY 0.872340 (-5550 6050);
PAINT AQUA (-5550 6050);
DISPLAY INVISIBLE (-5550 6050);
FORCEADD Q_RES..1
(-3525 875);
FORCEPROP 1 LAST LOCATION R9012
J 0
(-3750 875);
DISPLAY 0.638298 (-3750 875);
FORCEPROP 0 LAST $SEC 1
J 0
(-3750 925);
DISPLAY 0.680851 (-3750 925);
PAINT MONO (-3750 925);
DISPLAY INVISIBLE (-3750 925);
FORCEPROP 0 LAST CDS_SEC 1
J 0
(-3750 925);
DISPLAY 0.680851 (-3750 925);
DISPLAY INVISIBLE (-3750 925);
FORCEPROP 1 LASTPIN (-3625 875) $PN 1
J 0
(-3613 887);
DISPLAY 0.787234 (-3613 887);
PAINT MONO (-3613 887);
FORCEPROP 1 LASTPIN (-3425 875) $PN 2
J 0
(-3463 887);
DISPLAY 0.787234 (-3463 887);
PAINT MONO (-3463 887);
FORCEPROP 1 LAST VALUE 0
J 2
(-3375 875);
DISPLAY 0.510638 (-3375 875);
FORCEPROP 1 LAST TOLERANCE 5%
J 0
(-3350 875);
DISPLAY 0.510638 (-3350 875);
FORCEPROP 1 LAST MATERIAL CHIP
J 0
(-3275 875);
DISPLAY 0.510638 (-3275 875);
FORCEPROP 1 LAST PACK_TYPE 0402LF
J 0
(-3275 875);
DISPLAY 0.510638 (-3275 875);
DISPLAY INVISIBLE (-3275 875);
FORCEPROP 1 LAST WATTAGE 1/16W
J 2
(-3350 950);
DISPLAY 0.404255 (-3350 950);
DISPLAY INVISIBLE (-3350 950);
FORCEPROP 2 LAST CDS_LIB pure_quanta
J 0
(-3525 875);
DISPLAY INVISIBLE (-3525 875);
FORCEPROP 1 LAST PATH I39
J 0
(-3575 1025);
DISPLAY 0.978723 (-3575 1025);
PAINT WHITE (-3575 1025);
DISPLAY INVISIBLE (-3575 1025);
FORCEPROP 1 LAST PART_NUMBER CS00002JB13
J 0
(-3575 925);
DISPLAY 0.404255 (-3575 925);
DISPLAY INVISIBLE (-3575 925);
FORCEADD UNIVERSAL_POWER..1
(-7175 3525);
FORCEPROP 3 LASTPIN (-7175 3475) SIG_NAME P3V3_AUX\g
J 0
(-7165 3485);
DISPLAY 0.659574 (-7165 3485);
PAINT MONO (-7165 3485);
DISPLAY INVISIBLE (-7165 3485);
FORCEPROP 1 LAST HDL_POWER P3V3_AUX
J 1
(-7175 3575);
DISPLAY 0.872340 (-7175 3575);
PAINT GREEN (-7175 3575);
FORCEPROP 2 LAST CDS_LIB pure_quanta_power
J 0
(-7175 3525);
PAINT MONO (-7175 3525);
DISPLAY INVISIBLE (-7175 3525);
FORCEPROP 1 LAST PATH I4
J 0
(-7125 3550);
DISPLAY 0.872340 (-7125 3550);
PAINT AQUA (-7125 3550);
DISPLAY INVISIBLE (-7125 3550);
FORCEADD Q_RES..1
(-3525 975);
FORCEPROP 1 LAST LOCATION R9010
J 0
(-3750 975);
DISPLAY 0.638298 (-3750 975);
FORCEPROP 0 LAST $SEC 1
J 0
(-3750 1025);
DISPLAY 0.680851 (-3750 1025);
PAINT MONO (-3750 1025);
DISPLAY INVISIBLE (-3750 1025);
FORCEPROP 0 LAST CDS_SEC 1
J 0
(-3750 1025);
DISPLAY 0.680851 (-3750 1025);
DISPLAY INVISIBLE (-3750 1025);
FORCEPROP 1 LASTPIN (-3625 975) $PN 1
J 0
(-3613 987);
DISPLAY 0.787234 (-3613 987);
PAINT MONO (-3613 987);
FORCEPROP 1 LASTPIN (-3425 975) $PN 2
J 0
(-3463 987);
DISPLAY 0.787234 (-3463 987);
PAINT MONO (-3463 987);
FORCEPROP 1 LAST MATERIAL CHIP
J 0
(-3275 975);
DISPLAY 0.510638 (-3275 975);
FORCEPROP 1 LAST TOLERANCE 5%
J 0
(-3350 975);
DISPLAY 0.510638 (-3350 975);
FORCEPROP 1 LAST VALUE 0
J 2
(-3375 975);
DISPLAY 0.510638 (-3375 975);
FORCEPROP 2 LAST CDS_LIB pure_quanta
J 0
(-3525 975);
DISPLAY INVISIBLE (-3525 975);
FORCEPROP 1 LAST WATTAGE 1/16W
J 2
(-3350 1050);
DISPLAY 0.404255 (-3350 1050);
DISPLAY INVISIBLE (-3350 1050);
FORCEPROP 1 LAST PACK_TYPE 0402LF
J 0
(-3275 975);
DISPLAY 0.510638 (-3275 975);
DISPLAY INVISIBLE (-3275 975);
FORCEPROP 1 LAST PATH I40
J 0
(-3575 1125);
DISPLAY 0.978723 (-3575 1125);
PAINT WHITE (-3575 1125);
DISPLAY INVISIBLE (-3575 1125);
FORCEPROP 1 LAST PART_NUMBER CS00002JB13
J 0
(-3575 1025);
DISPLAY 0.404255 (-3575 1025);
DISPLAY INVISIBLE (-3575 1025);
FORCEADD Q_RES..1
(-3525 1075);
FORCEPROP 1 LAST LOCATION R8004
J 0
(-3750 1075);
DISPLAY 0.638298 (-3750 1075);
FORCEPROP 0 LAST $SEC 1
J 0
(-3750 1125);
DISPLAY 0.680851 (-3750 1125);
PAINT MONO (-3750 1125);
DISPLAY INVISIBLE (-3750 1125);
FORCEPROP 0 LAST CDS_SEC 1
J 0
(-3750 1125);
DISPLAY 0.680851 (-3750 1125);
DISPLAY INVISIBLE (-3750 1125);
FORCEPROP 1 LASTPIN (-3625 1075) $PN 1
J 0
(-3613 1087);
DISPLAY 0.787234 (-3613 1087);
PAINT MONO (-3613 1087);
FORCEPROP 1 LASTPIN (-3425 1075) $PN 2
J 0
(-3463 1087);
DISPLAY 0.787234 (-3463 1087);
PAINT MONO (-3463 1087);
FORCEPROP 1 LAST TOLERANCE 5%
J 0
(-3350 1075);
DISPLAY 0.510638 (-3350 1075);
FORCEPROP 1 LAST VALUE 0
J 2
(-3375 1075);
DISPLAY 0.510638 (-3375 1075);
FORCEPROP 1 LAST MATERIAL CHIP
J 0
(-3275 1075);
DISPLAY 0.510638 (-3275 1075);
FORCEPROP 1 LAST WATTAGE 1/16W
J 2
(-3350 1150);
DISPLAY 0.404255 (-3350 1150);
DISPLAY INVISIBLE (-3350 1150);
FORCEPROP 1 LAST PACK_TYPE 0402LF
J 0
(-3275 1075);
DISPLAY 0.510638 (-3275 1075);
DISPLAY INVISIBLE (-3275 1075);
FORCEPROP 2 LAST CDS_LIB pure_quanta
J 0
(-3525 1075);
DISPLAY INVISIBLE (-3525 1075);
FORCEPROP 1 LAST PATH I41
J 0
(-3575 1225);
DISPLAY 0.978723 (-3575 1225);
PAINT WHITE (-3575 1225);
DISPLAY INVISIBLE (-3575 1225);
FORCEPROP 1 LAST PART_NUMBER CS00002JB13
J 0
(-3575 1125);
DISPLAY 0.404255 (-3575 1125);
DISPLAY INVISIBLE (-3575 1125);
FORCEADD Q_RES..1
(-3525 1400);
FORCEPROP 1 LAST LOCATION R9019
J 0
(-3750 1400);
DISPLAY 0.638298 (-3750 1400);
FORCEPROP 0 LAST $SEC 1
J 0
(-3750 1450);
DISPLAY 0.680851 (-3750 1450);
PAINT MONO (-3750 1450);
DISPLAY INVISIBLE (-3750 1450);
FORCEPROP 0 LAST CDS_SEC 1
J 0
(-3750 1450);
DISPLAY 0.680851 (-3750 1450);
DISPLAY INVISIBLE (-3750 1450);
FORCEPROP 1 LASTPIN (-3625 1400) $PN 1
J 0
(-3613 1412);
DISPLAY 0.787234 (-3613 1412);
PAINT MONO (-3613 1412);
FORCEPROP 1 LASTPIN (-3425 1400) $PN 2
J 0
(-3463 1412);
DISPLAY 0.787234 (-3463 1412);
PAINT MONO (-3463 1412);
FORCEPROP 1 LAST VALUE 0
J 2
(-3375 1400);
DISPLAY 0.510638 (-3375 1400);
FORCEPROP 1 LAST MATERIAL CHIP
J 0
(-3275 1400);
DISPLAY 0.510638 (-3275 1400);
FORCEPROP 1 LAST TOLERANCE 5%
J 0
(-3350 1400);
DISPLAY 0.510638 (-3350 1400);
FORCEPROP 1 LAST PACK_TYPE 0402LF
J 0
(-3275 1400);
DISPLAY 0.510638 (-3275 1400);
DISPLAY INVISIBLE (-3275 1400);
FORCEPROP 1 LAST WATTAGE 1/16W
J 2
(-3350 1475);
DISPLAY 0.404255 (-3350 1475);
DISPLAY INVISIBLE (-3350 1475);
FORCEPROP 2 LAST CDS_LIB pure_quanta
J 0
(-3525 1400);
DISPLAY INVISIBLE (-3525 1400);
FORCEPROP 1 LAST PATH I42
J 0
(-3575 1550);
DISPLAY 0.978723 (-3575 1550);
PAINT WHITE (-3575 1550);
DISPLAY INVISIBLE (-3575 1550);
FORCEPROP 1 LAST PART_NUMBER CS00002JB13
J 0
(-3575 1450);
DISPLAY 0.404255 (-3575 1450);
DISPLAY INVISIBLE (-3575 1450);
FORCEADD Q_RES..1
(-3525 1500);
FORCEPROP 1 LAST LOCATION R9013
J 0
(-3750 1500);
DISPLAY 0.638298 (-3750 1500);
FORCEPROP 0 LAST $SEC 1
J 0
(-3750 1550);
DISPLAY 0.680851 (-3750 1550);
PAINT MONO (-3750 1550);
DISPLAY INVISIBLE (-3750 1550);
FORCEPROP 0 LAST CDS_SEC 1
J 0
(-3750 1550);
DISPLAY 0.680851 (-3750 1550);
DISPLAY INVISIBLE (-3750 1550);
FORCEPROP 1 LASTPIN (-3625 1500) $PN 1
J 0
(-3613 1512);
DISPLAY 0.787234 (-3613 1512);
PAINT MONO (-3613 1512);
FORCEPROP 1 LASTPIN (-3425 1500) $PN 2
J 0
(-3463 1512);
DISPLAY 0.787234 (-3463 1512);
PAINT MONO (-3463 1512);
FORCEPROP 1 LAST MATERIAL CHIP
J 0
(-3275 1500);
DISPLAY 0.510638 (-3275 1500);
FORCEPROP 1 LAST TOLERANCE 5%
J 0
(-3350 1500);
DISPLAY 0.510638 (-3350 1500);
FORCEPROP 1 LAST VALUE 0
J 2
(-3375 1500);
DISPLAY 0.510638 (-3375 1500);
FORCEPROP 2 LAST CDS_LIB pure_quanta
J 0
(-3525 1500);
DISPLAY INVISIBLE (-3525 1500);
FORCEPROP 1 LAST WATTAGE 1/16W
J 2
(-3350 1575);
DISPLAY 0.404255 (-3350 1575);
DISPLAY INVISIBLE (-3350 1575);
FORCEPROP 1 LAST PACK_TYPE 0402LF
J 0
(-3275 1500);
DISPLAY 0.510638 (-3275 1500);
DISPLAY INVISIBLE (-3275 1500);
FORCEPROP 1 LAST PATH I43
J 0
(-3575 1650);
DISPLAY 0.978723 (-3575 1650);
PAINT WHITE (-3575 1650);
DISPLAY INVISIBLE (-3575 1650);
FORCEPROP 1 LAST PART_NUMBER CS00002JB13
J 0
(-3575 1550);
DISPLAY 0.404255 (-3575 1550);
DISPLAY INVISIBLE (-3575 1550);
FORCEADD Q_RES..1
(-3525 1600);
FORCEPROP 1 LAST LOCATION R9018
J 0
(-3750 1600);
DISPLAY 0.638298 (-3750 1600);
FORCEPROP 0 LAST $SEC 1
J 0
(-3750 1650);
DISPLAY 0.680851 (-3750 1650);
PAINT MONO (-3750 1650);
DISPLAY INVISIBLE (-3750 1650);
FORCEPROP 0 LAST CDS_SEC 1
J 0
(-3750 1650);
DISPLAY 0.680851 (-3750 1650);
DISPLAY INVISIBLE (-3750 1650);
FORCEPROP 1 LASTPIN (-3625 1600) $PN 1
J 0
(-3613 1612);
DISPLAY 0.787234 (-3613 1612);
PAINT MONO (-3613 1612);
FORCEPROP 1 LASTPIN (-3425 1600) $PN 2
J 0
(-3463 1612);
DISPLAY 0.787234 (-3463 1612);
PAINT MONO (-3463 1612);
FORCEPROP 1 LAST MATERIAL CHIP
J 0
(-3275 1600);
DISPLAY 0.510638 (-3275 1600);
FORCEPROP 1 LAST TOLERANCE 5%
J 0
(-3350 1600);
DISPLAY 0.510638 (-3350 1600);
FORCEPROP 1 LAST VALUE 0
J 2
(-3375 1600);
DISPLAY 0.510638 (-3375 1600);
FORCEPROP 2 LAST CDS_LIB pure_quanta
J 0
(-3525 1600);
DISPLAY INVISIBLE (-3525 1600);
FORCEPROP 1 LAST WATTAGE 1/16W
J 2
(-3350 1675);
DISPLAY 0.404255 (-3350 1675);
DISPLAY INVISIBLE (-3350 1675);
FORCEPROP 1 LAST PACK_TYPE 0402LF
J 0
(-3275 1600);
DISPLAY 0.510638 (-3275 1600);
DISPLAY INVISIBLE (-3275 1600);
FORCEPROP 1 LAST PATH I44
J 0
(-3575 1750);
DISPLAY 0.978723 (-3575 1750);
PAINT WHITE (-3575 1750);
DISPLAY INVISIBLE (-3575 1750);
FORCEPROP 1 LAST PART_NUMBER CS00002JB13
J 0
(-3575 1650);
DISPLAY 0.404255 (-3575 1650);
DISPLAY INVISIBLE (-3575 1650);
FORCEADD Q_RES..1
(-3525 1700);
FORCEPROP 1 LAST LOCATION R9011
J 0
(-3750 1700);
DISPLAY 0.638298 (-3750 1700);
FORCEPROP 0 LAST $SEC 1
J 0
(-3750 1750);
DISPLAY 0.680851 (-3750 1750);
PAINT MONO (-3750 1750);
DISPLAY INVISIBLE (-3750 1750);
FORCEPROP 0 LAST CDS_SEC 1
J 0
(-3750 1750);
DISPLAY 0.680851 (-3750 1750);
DISPLAY INVISIBLE (-3750 1750);
FORCEPROP 1 LASTPIN (-3625 1700) $PN 1
J 0
(-3613 1712);
DISPLAY 0.787234 (-3613 1712);
PAINT MONO (-3613 1712);
FORCEPROP 1 LASTPIN (-3425 1700) $PN 2
J 0
(-3463 1712);
DISPLAY 0.787234 (-3463 1712);
PAINT MONO (-3463 1712);
FORCEPROP 1 LAST MATERIAL CHIP
J 0
(-3275 1700);
DISPLAY 0.510638 (-3275 1700);
FORCEPROP 1 LAST VALUE 0
J 2
(-3375 1700);
DISPLAY 0.510638 (-3375 1700);
FORCEPROP 1 LAST TOLERANCE 5%
J 0
(-3350 1700);
DISPLAY 0.510638 (-3350 1700);
FORCEPROP 2 LAST CDS_LIB pure_quanta
J 0
(-3525 1700);
DISPLAY INVISIBLE (-3525 1700);
FORCEPROP 1 LAST WATTAGE 1/16W
J 2
(-3350 1775);
DISPLAY 0.404255 (-3350 1775);
DISPLAY INVISIBLE (-3350 1775);
FORCEPROP 1 LAST PACK_TYPE 0402LF
J 0
(-3275 1700);
DISPLAY 0.510638 (-3275 1700);
DISPLAY INVISIBLE (-3275 1700);
FORCEPROP 1 LAST PATH I45
J 0
(-3575 1850);
DISPLAY 0.978723 (-3575 1850);
PAINT WHITE (-3575 1850);
DISPLAY INVISIBLE (-3575 1850);
FORCEPROP 1 LAST PART_NUMBER CS00002JB13
J 0
(-3575 1750);
DISPLAY 0.404255 (-3575 1750);
DISPLAY INVISIBLE (-3575 1750);
FORCEADD Q_RES..1
(-3525 1825);
FORCEPROP 1 LAST LOCATION R9001
J 0
(-3750 1825);
DISPLAY 0.638298 (-3750 1825);
FORCEPROP 0 LAST $SEC 1
J 0
(-3750 1875);
DISPLAY 0.680851 (-3750 1875);
PAINT MONO (-3750 1875);
DISPLAY INVISIBLE (-3750 1875);
FORCEPROP 0 LAST CDS_SEC 1
J 0
(-3750 1875);
DISPLAY 0.680851 (-3750 1875);
DISPLAY INVISIBLE (-3750 1875);
FORCEPROP 1 LASTPIN (-3625 1825) $PN 1
J 0
(-3613 1837);
DISPLAY 0.787234 (-3613 1837);
PAINT MONO (-3613 1837);
FORCEPROP 1 LASTPIN (-3425 1825) $PN 2
J 0
(-3463 1837);
DISPLAY 0.787234 (-3463 1837);
PAINT MONO (-3463 1837);
FORCEPROP 1 LAST MATERIAL CHIP
J 0
(-3275 1825);
DISPLAY 0.510638 (-3275 1825);
FORCEPROP 1 LAST VALUE 0
J 2
(-3375 1825);
DISPLAY 0.510638 (-3375 1825);
FORCEPROP 1 LAST TOLERANCE 5%
J 0
(-3350 1825);
DISPLAY 0.510638 (-3350 1825);
FORCEPROP 1 LAST PACK_TYPE 0402LF
J 0
(-3275 1825);
DISPLAY 0.510638 (-3275 1825);
DISPLAY INVISIBLE (-3275 1825);
FORCEPROP 1 LAST WATTAGE 1/16W
J 2
(-3350 1900);
DISPLAY 0.404255 (-3350 1900);
DISPLAY INVISIBLE (-3350 1900);
FORCEPROP 2 LAST CDS_LIB pure_quanta
J 0
(-3525 1825);
DISPLAY INVISIBLE (-3525 1825);
FORCEPROP 1 LAST PATH I46
J 0
(-3575 1975);
DISPLAY 0.978723 (-3575 1975);
PAINT WHITE (-3575 1975);
DISPLAY INVISIBLE (-3575 1975);
FORCEPROP 1 LAST PART_NUMBER CS00002JB13
J 0
(-3575 1875);
DISPLAY 0.404255 (-3575 1875);
DISPLAY INVISIBLE (-3575 1875);
FORCEADD Q_RES..1
(-3525 2250);
FORCEPROP 1 LAST LOCATION R3518
J 0
(-3750 2250);
DISPLAY 0.638298 (-3750 2250);
FORCEPROP 0 LAST $SEC 1
J 0
(-3575 2350);
DISPLAY 0.680851 (-3575 2350);
PAINT MONO (-3575 2350);
DISPLAY INVISIBLE (-3575 2350);
FORCEPROP 0 LAST CDS_SEC 1
J 0
(-3575 2350);
DISPLAY 1.021277 (-3575 2350);
DISPLAY INVISIBLE (-3575 2350);
FORCEPROP 1 LASTPIN (-3625 2250) $PN 1
J 0
(-3613 2262);
DISPLAY 0.787234 (-3613 2262);
PAINT MONO (-3613 2262);
FORCEPROP 1 LASTPIN (-3425 2250) $PN 2
J 0
(-3463 2262);
DISPLAY 0.787234 (-3463 2262);
PAINT MONO (-3463 2262);
FORCEPROP 1 LAST MATERIAL CHIP
J 0
(-3275 2250);
DISPLAY 0.510638 (-3275 2250);
FORCEPROP 1 LAST TOLERANCE 5%
J 0
(-3350 2250);
DISPLAY 0.510638 (-3350 2250);
FORCEPROP 1 LAST VALUE 0
J 2
(-3375 2250);
DISPLAY 0.510638 (-3375 2250);
FORCEPROP 2 LAST CDS_LIB pure_quanta
J 0
(-3525 2250);
DISPLAY INVISIBLE (-3525 2250);
FORCEPROP 1 LAST PACK_TYPE 0402LF
J 0
(-3275 2250);
DISPLAY 0.510638 (-3275 2250);
DISPLAY INVISIBLE (-3275 2250);
FORCEPROP 1 LAST WATTAGE 1/16W
J 2
(-3350 2325);
DISPLAY 0.404255 (-3350 2325);
DISPLAY INVISIBLE (-3350 2325);
FORCEPROP 1 LAST PATH I47
J 0
(-3575 2400);
DISPLAY 0.978723 (-3575 2400);
PAINT WHITE (-3575 2400);
DISPLAY INVISIBLE (-3575 2400);
FORCEPROP 1 LAST PART_NUMBER CS00002JB13
J 0
(-3575 2300);
DISPLAY 0.404255 (-3575 2300);
DISPLAY INVISIBLE (-3575 2300);
FORCEADD OFFPAGE..2
(-2225 875);
FORCEPROP 2 LAST $XR0 246 
J 0
(-2036 875);
DISPLAY 0.638298 (-2036 875);
PAINT MONO (-2036 875);
FORCEPROP 2 LAST CDS_LIB standard
J 0
(-2225 875);
DISPLAY INVISIBLE (-2225 875);
FORCEPROP 1 LAST OFFPAGE TRUE
J 0
(-1900 750);
DISPLAY 0.872340 (-1900 750);
PAINT GREEN (-1900 750);
DISPLAY INVISIBLE (-1900 750);
FORCEPROP 1 LAST COMMENT_BODY TRUE
J 0
(-2270 780);
DISPLAY 0.872340 (-2270 780);
PAINT PEACH (-2270 780);
DISPLAY INVISIBLE (-2270 780);
FORCEPROP 2 LAST PATH I48
J 0
(-2025 925);
DISPLAY 0.680851 (-2025 925);
DISPLAY INVISIBLE (-2025 925);
FORCEADD OFFPAGE..2
(-2225 975);
FORCEPROP 2 LAST $XR0 246 
J 0
(-2036 975);
DISPLAY 0.638298 (-2036 975);
PAINT MONO (-2036 975);
FORCEPROP 2 LAST CDS_LIB standard
J 0
(-2225 975);
DISPLAY INVISIBLE (-2225 975);
FORCEPROP 1 LAST OFFPAGE TRUE
J 0
(-1900 850);
DISPLAY 0.872340 (-1900 850);
PAINT GREEN (-1900 850);
DISPLAY INVISIBLE (-1900 850);
FORCEPROP 1 LAST COMMENT_BODY TRUE
J 0
(-2270 880);
DISPLAY 0.872340 (-2270 880);
PAINT PEACH (-2270 880);
DISPLAY INVISIBLE (-2270 880);
FORCEPROP 2 LAST PATH I49
J 0
(-2025 1025);
DISPLAY 0.680851 (-2025 1025);
DISPLAY INVISIBLE (-2025 1025);
FORCEADD UNIVERSAL_GND..1
(-6925 2300);
FORCEPROP 3 LASTPIN (-6925 2350) SIG_NAME GND\g
J 0
(-6915 2360);
DISPLAY 0.659574 (-6915 2360);
PAINT MONO (-6915 2360);
DISPLAY INVISIBLE (-6915 2360);
FORCEPROP 2 LAST CDS_LIB pure_quanta_power
J 0
(-6925 2300);
PAINT MONO (-6925 2300);
DISPLAY INVISIBLE (-6925 2300);
FORCEPROP 1 LAST HDL_POWER GND
J 1
(-6900 2225);
DISPLAY 0.872340 (-6900 2225);
PAINT GREEN (-6900 2225);
DISPLAY INVISIBLE (-6900 2225);
FORCEPROP 1 LAST PATH I5
J 0
(-6850 2300);
DISPLAY 0.872340 (-6850 2300);
PAINT AQUA (-6850 2300);
DISPLAY INVISIBLE (-6850 2300);
FORCEADD OFFPAGE..2
(-2225 1075);
FORCEPROP 2 LAST $XR0 246 
J 0
(-2036 1075);
DISPLAY 0.638298 (-2036 1075);
PAINT MONO (-2036 1075);
FORCEPROP 2 LAST CDS_LIB standard
J 0
(-2225 1075);
DISPLAY INVISIBLE (-2225 1075);
FORCEPROP 1 LAST OFFPAGE TRUE
J 0
(-1900 950);
DISPLAY 0.872340 (-1900 950);
PAINT GREEN (-1900 950);
DISPLAY INVISIBLE (-1900 950);
FORCEPROP 1 LAST COMMENT_BODY TRUE
J 0
(-2270 980);
DISPLAY 0.872340 (-2270 980);
PAINT PEACH (-2270 980);
DISPLAY INVISIBLE (-2270 980);
FORCEPROP 2 LAST PATH I50
J 0
(-2025 1125);
DISPLAY 0.680851 (-2025 1125);
DISPLAY INVISIBLE (-2025 1125);
FORCEADD OFFPAGE..2
(-2225 1400);
FORCEPROP 2 LAST $XR0 246 
J 0
(-2036 1400);
DISPLAY 0.638298 (-2036 1400);
PAINT MONO (-2036 1400);
FORCEPROP 2 LAST CDS_LIB standard
J 0
(-2225 1400);
DISPLAY INVISIBLE (-2225 1400);
FORCEPROP 1 LAST OFFPAGE TRUE
J 0
(-1900 1275);
DISPLAY 0.872340 (-1900 1275);
PAINT GREEN (-1900 1275);
DISPLAY INVISIBLE (-1900 1275);
FORCEPROP 1 LAST COMMENT_BODY TRUE
J 0
(-2270 1305);
DISPLAY 0.872340 (-2270 1305);
PAINT PEACH (-2270 1305);
DISPLAY INVISIBLE (-2270 1305);
FORCEPROP 2 LAST PATH I51
J 0
(-2025 1450);
DISPLAY 0.680851 (-2025 1450);
DISPLAY INVISIBLE (-2025 1450);
FORCEADD OFFPAGE..2
(-2225 1700);
FORCEPROP 2 LAST $XR0 246 
J 0
(-2036 1700);
DISPLAY 0.638298 (-2036 1700);
PAINT MONO (-2036 1700);
FORCEPROP 2 LAST CDS_LIB standard
J 0
(-2225 1700);
DISPLAY INVISIBLE (-2225 1700);
FORCEPROP 1 LAST OFFPAGE TRUE
J 0
(-1900 1575);
DISPLAY 0.872340 (-1900 1575);
PAINT GREEN (-1900 1575);
DISPLAY INVISIBLE (-1900 1575);
FORCEPROP 1 LAST COMMENT_BODY TRUE
J 0
(-2270 1605);
DISPLAY 0.872340 (-2270 1605);
PAINT PEACH (-2270 1605);
DISPLAY INVISIBLE (-2270 1605);
FORCEPROP 2 LAST PATH I52
J 0
(-2025 1750);
DISPLAY 0.680851 (-2025 1750);
DISPLAY INVISIBLE (-2025 1750);
FORCEADD OFFPAGE..2
(-2225 1825);
FORCEPROP 2 LAST $XR0 246 
J 0
(-2036 1825);
DISPLAY 0.638298 (-2036 1825);
PAINT MONO (-2036 1825);
FORCEPROP 2 LAST CDS_LIB standard
J 0
(-2225 1825);
DISPLAY INVISIBLE (-2225 1825);
FORCEPROP 1 LAST OFFPAGE TRUE
J 0
(-1900 1700);
DISPLAY 0.872340 (-1900 1700);
PAINT GREEN (-1900 1700);
DISPLAY INVISIBLE (-1900 1700);
FORCEPROP 1 LAST COMMENT_BODY TRUE
J 0
(-2270 1730);
DISPLAY 0.872340 (-2270 1730);
PAINT PEACH (-2270 1730);
DISPLAY INVISIBLE (-2270 1730);
FORCEPROP 2 LAST PATH I53
J 0
(-2025 1875);
DISPLAY 0.680851 (-2025 1875);
DISPLAY INVISIBLE (-2025 1875);
FORCEADD OFFPAGE..2
(-2250 2250);
FORCEPROP 2 LAST $XR0 246 
J 0
(-2061 2250);
DISPLAY 0.638298 (-2061 2250);
PAINT MONO (-2061 2250);
FORCEPROP 2 LAST CDS_LIB standard
J 0
(-2250 2250);
PAINT MONO (-2250 2250);
DISPLAY INVISIBLE (-2250 2250);
FORCEPROP 1 LAST OFFPAGE TRUE
J 0
(-1925 2125);
DISPLAY 0.872340 (-1925 2125);
PAINT GREEN (-1925 2125);
DISPLAY INVISIBLE (-1925 2125);
FORCEPROP 1 LAST COMMENT_BODY TRUE
J 0
(-2295 2155);
DISPLAY 0.872340 (-2295 2155);
PAINT PEACH (-2295 2155);
DISPLAY INVISIBLE (-2295 2155);
FORCEPROP 2 LAST PATH I54
J 0
(-2050 2300);
DISPLAY 0.680851 (-2050 2300);
DISPLAY INVISIBLE (-2050 2300);
FORCEADD Q_RES..1
(-3525 2450);
FORCEPROP 1 LAST LOCATION R3517
J 0
(-3750 2450);
DISPLAY 0.638298 (-3750 2450);
FORCEPROP 0 LAST $SEC 1
J 0
(-3575 2550);
DISPLAY 0.680851 (-3575 2550);
PAINT MONO (-3575 2550);
DISPLAY INVISIBLE (-3575 2550);
FORCEPROP 0 LAST CDS_SEC 1
J 0
(-3575 2550);
DISPLAY 1.021277 (-3575 2550);
DISPLAY INVISIBLE (-3575 2550);
FORCEPROP 1 LASTPIN (-3625 2450) $PN 1
J 0
(-3613 2462);
DISPLAY 0.787234 (-3613 2462);
PAINT MONO (-3613 2462);
FORCEPROP 1 LASTPIN (-3425 2450) $PN 2
J 0
(-3463 2462);
DISPLAY 0.787234 (-3463 2462);
PAINT MONO (-3463 2462);
FORCEPROP 1 LAST TOLERANCE 5%
J 0
(-3350 2450);
DISPLAY 0.510638 (-3350 2450);
FORCEPROP 1 LAST VALUE 0
J 2
(-3375 2450);
DISPLAY 0.510638 (-3375 2450);
FORCEPROP 1 LAST MATERIAL CHIP
J 0
(-3275 2450);
DISPLAY 0.510638 (-3275 2450);
FORCEPROP 2 LAST CDS_LIB pure_quanta
J 0
(-3525 2450);
DISPLAY INVISIBLE (-3525 2450);
FORCEPROP 1 LAST WATTAGE 1/16W
J 2
(-3350 2525);
DISPLAY 0.404255 (-3350 2525);
DISPLAY INVISIBLE (-3350 2525);
FORCEPROP 1 LAST PACK_TYPE 0402LF
J 0
(-3275 2450);
DISPLAY 0.510638 (-3275 2450);
DISPLAY INVISIBLE (-3275 2450);
FORCEPROP 1 LAST PATH I55
J 0
(-3575 2600);
DISPLAY 0.978723 (-3575 2600);
PAINT WHITE (-3575 2600);
DISPLAY INVISIBLE (-3575 2600);
FORCEPROP 1 LAST PART_NUMBER CS00002JB13
J 0
(-3575 2500);
DISPLAY 0.404255 (-3575 2500);
DISPLAY INVISIBLE (-3575 2500);
FORCEADD Q_RES..1
(-3525 2650);
FORCEPROP 1 LAST LOCATION R3516
J 0
(-3750 2650);
DISPLAY 0.638298 (-3750 2650);
FORCEPROP 0 LAST $SEC 1
J 0
(-3575 2750);
DISPLAY 0.680851 (-3575 2750);
PAINT MONO (-3575 2750);
DISPLAY INVISIBLE (-3575 2750);
FORCEPROP 0 LAST CDS_SEC 1
J 0
(-3575 2750);
DISPLAY 1.021277 (-3575 2750);
DISPLAY INVISIBLE (-3575 2750);
FORCEPROP 1 LASTPIN (-3625 2650) $PN 1
J 0
(-3613 2662);
DISPLAY 0.787234 (-3613 2662);
PAINT MONO (-3613 2662);
FORCEPROP 1 LASTPIN (-3425 2650) $PN 2
J 0
(-3463 2662);
DISPLAY 0.787234 (-3463 2662);
PAINT MONO (-3463 2662);
FORCEPROP 1 LAST TOLERANCE 5%
J 0
(-3350 2650);
DISPLAY 0.510638 (-3350 2650);
FORCEPROP 1 LAST MATERIAL CHIP
J 0
(-3275 2650);
DISPLAY 0.510638 (-3275 2650);
FORCEPROP 1 LAST VALUE 0
J 2
(-3375 2650);
DISPLAY 0.510638 (-3375 2650);
FORCEPROP 2 LAST CDS_LIB pure_quanta
J 0
(-3525 2650);
DISPLAY INVISIBLE (-3525 2650);
FORCEPROP 1 LAST PACK_TYPE 0402LF
J 0
(-3275 2650);
DISPLAY 0.510638 (-3275 2650);
DISPLAY INVISIBLE (-3275 2650);
FORCEPROP 1 LAST WATTAGE 1/16W
J 2
(-3350 2725);
DISPLAY 0.404255 (-3350 2725);
DISPLAY INVISIBLE (-3350 2725);
FORCEPROP 1 LAST PATH I56
J 0
(-3575 2800);
DISPLAY 0.978723 (-3575 2800);
PAINT WHITE (-3575 2800);
DISPLAY INVISIBLE (-3575 2800);
FORCEPROP 1 LAST PART_NUMBER CS00002JB13
J 0
(-3575 2700);
DISPLAY 0.404255 (-3575 2700);
DISPLAY INVISIBLE (-3575 2700);
FORCEADD Q_RES..1
(-3525 2850);
FORCEPROP 1 LAST LOCATION R3499
J 0
(-3725 2850);
DISPLAY 0.510638 (-3725 2850);
FORCEPROP 0 LAST $SEC 1
J 0
(-3275 2875);
DISPLAY 0.680851 (-3275 2875);
PAINT MONO (-3275 2875);
DISPLAY INVISIBLE (-3275 2875);
FORCEPROP 0 LAST CDS_SEC 1
J 0
(-3275 2875);
DISPLAY 1.021277 (-3275 2875);
DISPLAY INVISIBLE (-3275 2875);
FORCEPROP 1 LASTPIN (-3625 2850) $PN 1
J 0
(-3613 2862);
DISPLAY 0.787234 (-3613 2862);
PAINT MONO (-3613 2862);
FORCEPROP 1 LASTPIN (-3425 2850) $PN 2
J 0
(-3463 2862);
DISPLAY 0.787234 (-3463 2862);
PAINT MONO (-3463 2862);
FORCEPROP 1 LAST TOLERANCE 5%
J 0
(-3350 2850);
DISPLAY 0.510638 (-3350 2850);
FORCEPROP 1 LAST MATERIAL CHIP
J 0
(-3275 2850);
DISPLAY 0.510638 (-3275 2850);
FORCEPROP 1 LAST VALUE 0
J 2
(-3375 2850);
DISPLAY 0.510638 (-3375 2850);
FORCEPROP 1 LAST WATTAGE 1/16W
J 2
(-3350 2925);
DISPLAY 0.404255 (-3350 2925);
DISPLAY INVISIBLE (-3350 2925);
FORCEPROP 1 LAST PACK_TYPE 0402LF
J 0
(-3275 2850);
DISPLAY 0.510638 (-3275 2850);
DISPLAY INVISIBLE (-3275 2850);
FORCEPROP 2 LAST CDS_LIB pure_quanta
J 0
(-3525 2850);
DISPLAY INVISIBLE (-3525 2850);
FORCEPROP 1 LAST PATH I57
J 0
(-3575 3000);
DISPLAY 0.978723 (-3575 3000);
PAINT WHITE (-3575 3000);
DISPLAY INVISIBLE (-3575 3000);
FORCEPROP 1 LAST PART_NUMBER CS00002JB13
J 0
(-3575 2900);
DISPLAY 0.404255 (-3575 2900);
DISPLAY INVISIBLE (-3575 2900);
FORCEADD Q_RES..1
(-3525 3050);
FORCEPROP 1 LAST LOCATION R2983
J 0
(-3725 3050);
DISPLAY 0.510638 (-3725 3050);
FORCEPROP 0 LAST $SEC 1
J 0
(-3275 3075);
DISPLAY 0.680851 (-3275 3075);
PAINT MONO (-3275 3075);
DISPLAY INVISIBLE (-3275 3075);
FORCEPROP 0 LAST CDS_SEC 1
J 0
(-3275 3075);
DISPLAY 1.021277 (-3275 3075);
DISPLAY INVISIBLE (-3275 3075);
FORCEPROP 1 LASTPIN (-3625 3050) $PN 1
J 0
(-3613 3062);
DISPLAY 0.787234 (-3613 3062);
PAINT MONO (-3613 3062);
FORCEPROP 1 LASTPIN (-3425 3050) $PN 2
J 0
(-3463 3062);
DISPLAY 0.787234 (-3463 3062);
PAINT MONO (-3463 3062);
FORCEPROP 1 LAST MATERIAL CHIP
J 0
(-3275 3050);
DISPLAY 0.510638 (-3275 3050);
FORCEPROP 1 LAST TOLERANCE 5%
J 0
(-3350 3050);
DISPLAY 0.510638 (-3350 3050);
FORCEPROP 1 LAST VALUE 0
J 2
(-3375 3050);
DISPLAY 0.510638 (-3375 3050);
FORCEPROP 2 LAST CDS_LIB pure_quanta
J 0
(-3525 3050);
DISPLAY INVISIBLE (-3525 3050);
FORCEPROP 1 LAST PACK_TYPE 0402LF
J 0
(-3275 3050);
DISPLAY 0.510638 (-3275 3050);
DISPLAY INVISIBLE (-3275 3050);
FORCEPROP 1 LAST WATTAGE 1/16W
J 2
(-3350 3125);
DISPLAY 0.404255 (-3350 3125);
DISPLAY INVISIBLE (-3350 3125);
FORCEPROP 1 LAST PATH I58
J 0
(-3575 3200);
DISPLAY 0.978723 (-3575 3200);
PAINT WHITE (-3575 3200);
DISPLAY INVISIBLE (-3575 3200);
FORCEPROP 1 LAST PART_NUMBER CS00002JB13
J 0
(-3575 3100);
DISPLAY 0.404255 (-3575 3100);
DISPLAY INVISIBLE (-3575 3100);
FORCEADD Q_RES..1
(-3525 3475);
FORCEPROP 1 LAST LOCATION R2848
J 0
(-3725 3475);
DISPLAY 0.510638 (-3725 3475);
FORCEPROP 0 LAST $SEC 1
J 0
(-3275 3500);
DISPLAY 0.680851 (-3275 3500);
PAINT MONO (-3275 3500);
DISPLAY INVISIBLE (-3275 3500);
FORCEPROP 0 LAST CDS_SEC 1
J 0
(-3275 3500);
DISPLAY 1.021277 (-3275 3500);
DISPLAY INVISIBLE (-3275 3500);
FORCEPROP 1 LASTPIN (-3625 3475) $PN 1
J 0
(-3613 3487);
DISPLAY 0.787234 (-3613 3487);
PAINT MONO (-3613 3487);
FORCEPROP 1 LASTPIN (-3425 3475) $PN 2
J 0
(-3463 3487);
DISPLAY 0.787234 (-3463 3487);
PAINT MONO (-3463 3487);
FORCEPROP 1 LAST MATERIAL CHIP
J 0
(-3275 3475);
DISPLAY 0.510638 (-3275 3475);
FORCEPROP 1 LAST VALUE 0
J 2
(-3375 3475);
DISPLAY 0.510638 (-3375 3475);
FORCEPROP 1 LAST TOLERANCE 5%
J 0
(-3350 3475);
DISPLAY 0.510638 (-3350 3475);
FORCEPROP 1 LAST WATTAGE 1/16W
J 2
(-3350 3550);
DISPLAY 0.404255 (-3350 3550);
DISPLAY INVISIBLE (-3350 3550);
FORCEPROP 1 LAST PACK_TYPE 0402LF
J 0
(-3275 3475);
DISPLAY 0.510638 (-3275 3475);
DISPLAY INVISIBLE (-3275 3475);
FORCEPROP 2 LAST CDS_LIB pure_quanta
J 0
(-3525 3475);
DISPLAY INVISIBLE (-3525 3475);
FORCEPROP 1 LAST PATH I59
J 0
(-3575 3625);
DISPLAY 0.978723 (-3575 3625);
PAINT WHITE (-3575 3625);
DISPLAY INVISIBLE (-3575 3625);
FORCEPROP 1 LAST PART_NUMBER CS00002JB13
J 0
(-3575 3525);
DISPLAY 0.404255 (-3575 3525);
DISPLAY INVISIBLE (-3575 3525);
FORCEADD Q_RES..2
(-6925 2525);
FORCEPROP 1 LAST LOCATION R2696
J 0
(-6880 2650);
DISPLAY 0.638298 (-6880 2650);
FORCEPROP 0 LAST $SEC 1
J 0
(-6875 2700);
DISPLAY 0.680851 (-6875 2700);
PAINT MONO (-6875 2700);
DISPLAY INVISIBLE (-6875 2700);
FORCEPROP 0 LAST CDS_SEC 1
J 0
(-6875 2700);
DISPLAY 1.021277 (-6875 2700);
DISPLAY INVISIBLE (-6875 2700);
FORCEPROP 1 LASTPIN (-6925 2625) $PN 1
J 0
(-6920 2587);
DISPLAY 0.787234 (-6920 2587);
PAINT MONO (-6920 2587);
FORCEPROP 1 LASTPIN (-6925 2425) $PN 2
J 0
(-6920 2435);
DISPLAY 0.787234 (-6920 2435);
PAINT MONO (-6920 2435);
FORCEPROP 1 LAST MATERIAL CHIP
J 0
(-6885 2450);
DISPLAY 0.638298 (-6885 2450);
FORCEPROP 1 LAST VALUE 1K
J 0
(-6880 2600);
DISPLAY 0.638298 (-6880 2600);
FORCEPROP 1 LAST TOLERANCE 1%
J 0
(-6880 2550);
DISPLAY 0.638298 (-6880 2550);
FORCEPROP 1 LAST WATTAGE 1/16W
J 0
(-6885 2500);
DISPLAY 0.638298 (-6885 2500);
FORCEPROP 1 LAST PACK_TYPE 0402LF
J 0
(-6885 2400);
DISPLAY 0.638298 (-6885 2400);
FORCEPROP 2 LAST CDS_LIB pure_quanta
J 0
(-6925 2525);
DISPLAY INVISIBLE (-6925 2525);
FORCEPROP 1 LAST PATH I6
J 0
(-6875 2700);
DISPLAY 0.978723 (-6875 2700);
PAINT WHITE (-6875 2700);
DISPLAY INVISIBLE (-6875 2700);
FORCEPROP 1 LAST PART_NUMBER CS21002FB06
J 0
(-6885 2350);
DISPLAY 0.638298 (-6885 2350);
DISPLAY INVISIBLE (-6885 2350);
FORCEADD UNIVERSAL_GND..1
(-3275 3675);
FORCEPROP 3 LASTPIN (-3275 3725) SIG_NAME GND\g
J 0
(-3265 3735);
DISPLAY 0.659574 (-3265 3735);
PAINT MONO (-3265 3735);
DISPLAY INVISIBLE (-3265 3735);
FORCEPROP 2 LAST CDS_LIB pure_quanta_power
J 0
(-3275 3675);
PAINT MONO (-3275 3675);
DISPLAY INVISIBLE (-3275 3675);
FORCEPROP 1 LAST HDL_POWER GND
J 1
(-3250 3600);
DISPLAY 0.872340 (-3250 3600);
PAINT GREEN (-3250 3600);
DISPLAY INVISIBLE (-3250 3600);
FORCEPROP 1 LAST PATH I60
J 0
(-3200 3675);
DISPLAY 0.872340 (-3200 3675);
PAINT AQUA (-3200 3675);
DISPLAY INVISIBLE (-3200 3675);
FORCEADD Q_CAP..1
R 2
(-3275 3900);
FORCEPROP 1 LAST LOCATION C1713
J 2
(-3325 4000);
DISPLAY 0.787234 (-3325 4000);
FORCEPROP 0 LAST $SEC 1
J 0
(-3325 4050);
DISPLAY 0.680851 (-3325 4050);
PAINT MONO (-3325 4050);
DISPLAY INVISIBLE (-3325 4050);
FORCEPROP 0 LAST CDS_SEC 1
J 0
(-3325 4050);
DISPLAY 1.021277 (-3325 4050);
DISPLAY INVISIBLE (-3325 4050);
FORCEPROP 1 LASTPIN (-3275 4000) $PN 1
J 2
(-3285 3980);
DISPLAY 0.787234 (-3285 3980);
PAINT MONO (-3285 3980);
FORCEPROP 1 LASTPIN (-3275 3800) $PN 2
J 2
(-3285 3780);
DISPLAY 0.787234 (-3285 3780);
PAINT MONO (-3285 3780);
FORCEPROP 1 LAST TOLERANCE 10%
J 2
(-3325 3850);
DISPLAY 0.510638 (-3325 3850);
FORCEPROP 1 LAST VOLTAGE 25V
J 2
(-3325 3900);
DISPLAY 0.510638 (-3325 3900);
FORCEPROP 1 LAST MATERIAL X7R
J 2
(-3325 3800);
DISPLAY 0.510638 (-3325 3800);
FORCEPROP 1 LAST VALUE 0.1UF
J 2
(-3325 3950);
DISPLAY 0.510638 (-3325 3950);
FORCEPROP 1 LAST PACK_TYPE 0402
J 2
(-3325 3700);
DISPLAY 0.510638 (-3325 3700);
FORCEPROP 2 LAST CDS_LIB pure_quanta
J 0
(-3275 3900);
DISPLAY INVISIBLE (-3275 3900);
FORCEPROP 1 LAST PATH I61
J 2
(-3325 4050);
DISPLAY 0.978723 (-3325 4050);
PAINT WHITE (-3325 4050);
DISPLAY INVISIBLE (-3325 4050);
FORCEPROP 1 LAST PART_NUMBER CH4104K1B00
J 2
(-3325 3750);
DISPLAY 0.510638 (-3325 3750);
DISPLAY INVISIBLE (-3325 3750);
FORCEADD UNIVERSAL_POWER..1
(-3275 4175);
FORCEPROP 3 LASTPIN (-3275 4125) SIG_NAME P3V3_AUX\g
J 0
(-3265 4135);
DISPLAY 0.659574 (-3265 4135);
PAINT MONO (-3265 4135);
DISPLAY INVISIBLE (-3265 4135);
FORCEPROP 1 LAST HDL_POWER P3V3_AUX
J 1
(-3275 4225);
DISPLAY 0.872340 (-3275 4225);
PAINT GREEN (-3275 4225);
FORCEPROP 2 LAST CDS_LIB pure_quanta_power
J 0
(-3275 4175);
PAINT MONO (-3275 4175);
DISPLAY INVISIBLE (-3275 4175);
FORCEPROP 1 LAST PATH I62
J 0
(-3225 4200);
DISPLAY 0.872340 (-3225 4200);
PAINT AQUA (-3225 4200);
DISPLAY INVISIBLE (-3225 4200);
FORCEADD OFFPAGE..2
(-2250 2450);
FORCEPROP 2 LAST $XR0 246 
J 0
(-2061 2450);
DISPLAY 0.638298 (-2061 2450);
PAINT MONO (-2061 2450);
FORCEPROP 2 LAST CDS_LIB standard
J 0
(-2250 2450);
PAINT MONO (-2250 2450);
DISPLAY INVISIBLE (-2250 2450);
FORCEPROP 1 LAST OFFPAGE TRUE
J 0
(-1925 2325);
DISPLAY 0.872340 (-1925 2325);
PAINT GREEN (-1925 2325);
DISPLAY INVISIBLE (-1925 2325);
FORCEPROP 1 LAST COMMENT_BODY TRUE
J 0
(-2295 2355);
DISPLAY 0.872340 (-2295 2355);
PAINT PEACH (-2295 2355);
DISPLAY INVISIBLE (-2295 2355);
FORCEPROP 2 LAST PATH I63
J 0
(-2050 2500);
DISPLAY 0.680851 (-2050 2500);
DISPLAY INVISIBLE (-2050 2500);
FORCEADD OFFPAGE..2
(-2250 2650);
FORCEPROP 2 LAST $XR0 246 
J 0
(-2061 2650);
DISPLAY 0.638298 (-2061 2650);
PAINT MONO (-2061 2650);
FORCEPROP 2 LAST CDS_LIB standard
J 0
(-2250 2650);
PAINT MONO (-2250 2650);
DISPLAY INVISIBLE (-2250 2650);
FORCEPROP 1 LAST OFFPAGE TRUE
J 0
(-1925 2525);
DISPLAY 0.872340 (-1925 2525);
PAINT GREEN (-1925 2525);
DISPLAY INVISIBLE (-1925 2525);
FORCEPROP 1 LAST COMMENT_BODY TRUE
J 0
(-2295 2555);
DISPLAY 0.872340 (-2295 2555);
PAINT PEACH (-2295 2555);
DISPLAY INVISIBLE (-2295 2555);
FORCEPROP 2 LAST PATH I64
J 0
(-2050 2700);
DISPLAY 0.680851 (-2050 2700);
DISPLAY INVISIBLE (-2050 2700);
FORCEADD OFFPAGE..2
(-2250 2850);
FORCEPROP 2 LAST $XR0 246 
J 0
(-2061 2850);
DISPLAY 0.638298 (-2061 2850);
PAINT MONO (-2061 2850);
FORCEPROP 2 LAST CDS_LIB standard
J 0
(-2250 2850);
PAINT MONO (-2250 2850);
DISPLAY INVISIBLE (-2250 2850);
FORCEPROP 1 LAST OFFPAGE TRUE
J 0
(-1925 2725);
DISPLAY 0.872340 (-1925 2725);
PAINT GREEN (-1925 2725);
DISPLAY INVISIBLE (-1925 2725);
FORCEPROP 1 LAST COMMENT_BODY TRUE
J 0
(-2295 2755);
DISPLAY 0.872340 (-2295 2755);
PAINT PEACH (-2295 2755);
DISPLAY INVISIBLE (-2295 2755);
FORCEPROP 2 LAST PATH I65
J 0
(-2050 2900);
DISPLAY 0.680851 (-2050 2900);
DISPLAY INVISIBLE (-2050 2900);
FORCEADD OFFPAGE..2
(-2250 3050);
FORCEPROP 2 LAST $XR0 246 
J 0
(-2061 3050);
DISPLAY 0.638298 (-2061 3050);
PAINT MONO (-2061 3050);
FORCEPROP 2 LAST CDS_LIB standard
J 0
(-2250 3050);
PAINT MONO (-2250 3050);
DISPLAY INVISIBLE (-2250 3050);
FORCEPROP 1 LAST OFFPAGE TRUE
J 0
(-1925 2925);
DISPLAY 0.872340 (-1925 2925);
PAINT GREEN (-1925 2925);
DISPLAY INVISIBLE (-1925 2925);
FORCEPROP 1 LAST COMMENT_BODY TRUE
J 0
(-2295 2955);
DISPLAY 0.872340 (-2295 2955);
PAINT PEACH (-2295 2955);
DISPLAY INVISIBLE (-2295 2955);
FORCEPROP 2 LAST PATH I66
J 0
(-2050 3100);
DISPLAY 0.680851 (-2050 3100);
DISPLAY INVISIBLE (-2050 3100);
FORCEADD OFFPAGE..2
(-2250 3250);
FORCEPROP 2 LAST $XR0 246 
J 0
(-2061 3250);
DISPLAY 0.638298 (-2061 3250);
PAINT MONO (-2061 3250);
FORCEPROP 2 LAST CDS_LIB standard
J 0
(-2250 3250);
PAINT MONO (-2250 3250);
DISPLAY INVISIBLE (-2250 3250);
FORCEPROP 1 LAST OFFPAGE TRUE
J 0
(-1925 3125);
DISPLAY 0.872340 (-1925 3125);
PAINT GREEN (-1925 3125);
DISPLAY INVISIBLE (-1925 3125);
FORCEPROP 1 LAST COMMENT_BODY TRUE
J 0
(-2295 3155);
DISPLAY 0.872340 (-2295 3155);
PAINT PEACH (-2295 3155);
DISPLAY INVISIBLE (-2295 3155);
FORCEPROP 2 LAST PATH I67
J 0
(-2050 3300);
DISPLAY 0.680851 (-2050 3300);
DISPLAY INVISIBLE (-2050 3300);
FORCEADD OFFPAGE..2
(-2250 3475);
FORCEPROP 2 LAST $XR0 130 
J 0
(-2061 3475);
DISPLAY 0.638298 (-2061 3475);
PAINT MONO (-2061 3475);
FORCEPROP 2 LAST CDS_LIB standard
J 0
(-2250 3475);
PAINT MONO (-2250 3475);
DISPLAY INVISIBLE (-2250 3475);
FORCEPROP 1 LAST OFFPAGE TRUE
J 0
(-1925 3350);
DISPLAY 0.872340 (-1925 3350);
PAINT GREEN (-1925 3350);
DISPLAY INVISIBLE (-1925 3350);
FORCEPROP 1 LAST COMMENT_BODY TRUE
J 0
(-2295 3380);
DISPLAY 0.872340 (-2295 3380);
PAINT PEACH (-2295 3380);
DISPLAY INVISIBLE (-2295 3380);
FORCEPROP 2 LAST PATH I68
J 0
(-2050 3525);
DISPLAY 0.680851 (-2050 3525);
DISPLAY INVISIBLE (-2050 3525);
FORCEADD OFFPAGE..3
(-2850 4500);
FORCEPROP 2 LAST $XR0 246 
J 0
(-2636 4500);
DISPLAY 0.638298 (-2636 4500);
PAINT MONO (-2636 4500);
FORCEPROP 2 LAST CDS_LIB standard
J 2
(-2850 4500);
PAINT MONO (-2850 4500);
DISPLAY INVISIBLE (-2850 4500);
FORCEPROP 1 LAST OFFPAGE TRUE
J 0
(-2525 4375);
DISPLAY 0.872340 (-2525 4375);
DISPLAY INVISIBLE (-2525 4375);
FORCEPROP 1 LAST COMMENT_BODY TRUE
J 0
(-2900 4400);
DISPLAY 0.872340 (-2900 4400);
PAINT GREEN (-2900 4400);
DISPLAY INVISIBLE (-2900 4400);
FORCEPROP 2 LAST PATH I69
J 0
(-2625 4550);
DISPLAY 0.680851 (-2625 4550);
DISPLAY INVISIBLE (-2625 4550);
FORCEADD Q_RES..2
(-6925 3125);
FORCEPROP 1 LAST LOCATION R2695
J 0
(-6880 3250);
DISPLAY 0.638298 (-6880 3250);
FORCEPROP 0 LAST $SEC 1
J 0
(-6875 3300);
DISPLAY 0.680851 (-6875 3300);
PAINT MONO (-6875 3300);
DISPLAY INVISIBLE (-6875 3300);
FORCEPROP 0 LAST CDS_SEC 1
J 0
(-6875 3300);
DISPLAY 1.021277 (-6875 3300);
DISPLAY INVISIBLE (-6875 3300);
FORCEPROP 1 LASTPIN (-6925 3225) $PN 1
J 0
(-6920 3187);
DISPLAY 0.787234 (-6920 3187);
PAINT MONO (-6920 3187);
FORCEPROP 1 LASTPIN (-6925 3025) $PN 2
J 0
(-6920 3035);
DISPLAY 0.787234 (-6920 3035);
PAINT MONO (-6920 3035);
FORCEPROP 1 LAST WATTAGE 1/16W
J 0
(-6885 3100);
DISPLAY 0.638298 (-6885 3100);
FORCEPROP 1 LAST VALUE 1K
J 0
(-6880 3200);
DISPLAY 0.638298 (-6880 3200);
FORCEPROP 1 LAST TOLERANCE 1%
J 0
(-6880 3150);
DISPLAY 0.638298 (-6880 3150);
FORCEPROP 1 LAST MATERIAL EMPTY
J 0
(-6885 3050);
DISPLAY 0.638298 (-6885 3050);
PAINT RED (-6885 3050);
FORCEPROP 1 LAST PACK_TYPE 0402LF
J 0
(-6885 3000);
DISPLAY 0.638298 (-6885 3000);
FORCEPROP 2 LAST CDS_LIB pure_quanta
J 0
(-6925 3125);
DISPLAY INVISIBLE (-6925 3125);
FORCEPROP 1 LAST PATH I7
J 0
(-6875 3300);
DISPLAY 0.978723 (-6875 3300);
PAINT WHITE (-6875 3300);
DISPLAY INVISIBLE (-6875 3300);
FORCEPROP 1 LAST PART_NUMBER CS21002FB06
J 0
(-6885 2950);
DISPLAY 0.638298 (-6885 2950);
DISPLAY INVISIBLE (-6885 2950);
FORCEADD OFFPAGE..1
R 2
(-2850 4600);
FORCEPROP 2 LAST $XR0 246 
J 0
(-2664 4600);
DISPLAY 0.638298 (-2664 4600);
PAINT MONO (-2664 4600);
FORCEPROP 2 LAST CDS_LIB standard
J 2
(-2850 4600);
PAINT MONO (-2850 4600);
DISPLAY INVISIBLE (-2850 4600);
FORCEPROP 1 LAST OFFPAGE TRUE
J 2
(-3175 4475);
DISPLAY 0.872340 (-3175 4475);
PAINT GREEN (-3175 4475);
DISPLAY INVISIBLE (-3175 4475);
FORCEPROP 1 LAST COMMENT_BODY TRUE
J 2
(-2975 4500);
DISPLAY 0.872340 (-2975 4500);
PAINT GREEN (-2975 4500);
DISPLAY INVISIBLE (-2975 4500);
FORCEPROP 2 LAST PATH I70
J 0
(-2650 4650);
DISPLAY 0.680851 (-2650 4650);
DISPLAY INVISIBLE (-2650 4650);
FORCEADD OFFPAGE..1
R 2
(-2850 4800);
FORCEPROP 2 LAST $XR0 246 
J 0
(-2664 4800);
DISPLAY 0.638298 (-2664 4800);
PAINT MONO (-2664 4800);
FORCEPROP 2 LAST CDS_LIB standard
J 0
(-2850 4800);
DISPLAY INVISIBLE (-2850 4800);
FORCEPROP 1 LAST OFFPAGE TRUE
J 2
(-3175 4675);
DISPLAY 0.872340 (-3175 4675);
PAINT GREEN (-3175 4675);
DISPLAY INVISIBLE (-3175 4675);
FORCEPROP 1 LAST COMMENT_BODY TRUE
J 2
(-2975 4700);
DISPLAY 0.872340 (-2975 4700);
PAINT GREEN (-2975 4700);
DISPLAY INVISIBLE (-2975 4700);
FORCEPROP 2 LAST PATH I71
J 0
(-2650 4850);
DISPLAY 0.680851 (-2650 4850);
DISPLAY INVISIBLE (-2650 4850);
FORCEADD OFFPAGE..1
R 2
(-2850 4700);
FORCEPROP 2 LAST $XR0 246 
J 0
(-2664 4700);
DISPLAY 0.638298 (-2664 4700);
PAINT MONO (-2664 4700);
FORCEPROP 2 LAST CDS_LIB standard
J 2
(-2850 4700);
DISPLAY INVISIBLE (-2850 4700);
FORCEPROP 1 LAST OFFPAGE TRUE
J 2
(-3175 4575);
DISPLAY 0.872340 (-3175 4575);
PAINT GREEN (-3175 4575);
DISPLAY INVISIBLE (-3175 4575);
FORCEPROP 1 LAST COMMENT_BODY TRUE
J 2
(-2975 4600);
DISPLAY 0.872340 (-2975 4600);
PAINT GREEN (-2975 4600);
DISPLAY INVISIBLE (-2975 4600);
FORCEPROP 2 LAST PATH I72
J 0
(-2650 4750);
DISPLAY 0.680851 (-2650 4750);
DISPLAY INVISIBLE (-2650 4750);
FORCEADD OFFPAGE..1
R 2
(-2850 4900);
FORCEPROP 2 LAST $XR0 246 
J 0
(-2664 4900);
DISPLAY 0.638298 (-2664 4900);
PAINT MONO (-2664 4900);
FORCEPROP 2 LAST CDS_LIB standard
J 0
(-2850 4900);
DISPLAY INVISIBLE (-2850 4900);
FORCEPROP 1 LAST OFFPAGE TRUE
J 2
(-3175 4775);
DISPLAY 0.872340 (-3175 4775);
PAINT GREEN (-3175 4775);
DISPLAY INVISIBLE (-3175 4775);
FORCEPROP 1 LAST COMMENT_BODY TRUE
J 2
(-2975 4800);
DISPLAY 0.872340 (-2975 4800);
PAINT GREEN (-2975 4800);
DISPLAY INVISIBLE (-2975 4800);
FORCEPROP 2 LAST PATH I73
J 0
(-2650 4950);
DISPLAY 0.680851 (-2650 4950);
DISPLAY INVISIBLE (-2650 4950);
FORCEADD OFFPAGE..1
R 2
(-2850 5000);
FORCEPROP 2 LAST $XR0 246 
J 0
(-2664 5000);
DISPLAY 0.638298 (-2664 5000);
PAINT MONO (-2664 5000);
FORCEPROP 2 LAST CDS_LIB standard
J 0
(-2850 5000);
DISPLAY INVISIBLE (-2850 5000);
FORCEPROP 1 LAST OFFPAGE TRUE
J 2
(-3175 4875);
DISPLAY 0.872340 (-3175 4875);
PAINT GREEN (-3175 4875);
DISPLAY INVISIBLE (-3175 4875);
FORCEPROP 1 LAST COMMENT_BODY TRUE
J 2
(-2975 4900);
DISPLAY 0.872340 (-2975 4900);
PAINT GREEN (-2975 4900);
DISPLAY INVISIBLE (-2975 4900);
FORCEPROP 2 LAST PATH I74
J 0
(-2650 5050);
DISPLAY 0.680851 (-2650 5050);
DISPLAY INVISIBLE (-2650 5050);
FORCEADD OFFPAGE..1
R 2
(-2850 5100);
FORCEPROP 2 LAST $XR0 246 
J 0
(-2664 5100);
DISPLAY 0.638298 (-2664 5100);
PAINT MONO (-2664 5100);
FORCEPROP 2 LAST CDS_LIB standard
J 0
(-2850 5100);
DISPLAY INVISIBLE (-2850 5100);
FORCEPROP 1 LAST OFFPAGE TRUE
J 2
(-3175 4975);
DISPLAY 0.872340 (-3175 4975);
PAINT GREEN (-3175 4975);
DISPLAY INVISIBLE (-3175 4975);
FORCEPROP 1 LAST COMMENT_BODY TRUE
J 2
(-2975 5000);
DISPLAY 0.872340 (-2975 5000);
PAINT GREEN (-2975 5000);
DISPLAY INVISIBLE (-2975 5000);
FORCEPROP 2 LAST PATH I75
J 0
(-2650 5150);
DISPLAY 0.680851 (-2650 5150);
DISPLAY INVISIBLE (-2650 5150);
FORCEADD OFFPAGE..1
R 2
(-2850 5200);
FORCEPROP 2 LAST $XR0 246 
J 0
(-2664 5200);
DISPLAY 0.638298 (-2664 5200);
PAINT MONO (-2664 5200);
FORCEPROP 2 LAST CDS_LIB standard
J 0
(-2850 5200);
DISPLAY INVISIBLE (-2850 5200);
FORCEPROP 1 LAST OFFPAGE TRUE
J 2
(-3175 5075);
DISPLAY 0.872340 (-3175 5075);
PAINT GREEN (-3175 5075);
DISPLAY INVISIBLE (-3175 5075);
FORCEPROP 1 LAST COMMENT_BODY TRUE
J 2
(-2975 5100);
DISPLAY 0.872340 (-2975 5100);
PAINT GREEN (-2975 5100);
DISPLAY INVISIBLE (-2975 5100);
FORCEPROP 2 LAST PATH I76
J 0
(-2650 5250);
DISPLAY 0.680851 (-2650 5250);
DISPLAY INVISIBLE (-2650 5250);
FORCEADD OFFPAGE..1
R 2
(-2850 5300);
FORCEPROP 2 LAST $XR0 246 
J 0
(-2664 5300);
DISPLAY 0.638298 (-2664 5300);
PAINT MONO (-2664 5300);
FORCEPROP 2 LAST CDS_LIB standard
J 0
(-2850 5300);
DISPLAY INVISIBLE (-2850 5300);
FORCEPROP 1 LAST OFFPAGE TRUE
J 2
(-3175 5175);
DISPLAY 0.872340 (-3175 5175);
PAINT GREEN (-3175 5175);
DISPLAY INVISIBLE (-3175 5175);
FORCEPROP 1 LAST COMMENT_BODY TRUE
J 2
(-2975 5200);
DISPLAY 0.872340 (-2975 5200);
PAINT GREEN (-2975 5200);
DISPLAY INVISIBLE (-2975 5200);
FORCEPROP 2 LAST PATH I77
J 0
(-2650 5350);
DISPLAY 0.680851 (-2650 5350);
DISPLAY INVISIBLE (-2650 5350);
FORCEADD OFFPAGE..1
R 2
(-2850 5500);
FORCEPROP 2 LAST $XR0 246 
J 0
(-2664 5500);
DISPLAY 0.638298 (-2664 5500);
PAINT MONO (-2664 5500);
FORCEPROP 2 LAST CDS_LIB standard
J 0
(-2850 5500);
DISPLAY INVISIBLE (-2850 5500);
FORCEPROP 1 LAST OFFPAGE TRUE
J 2
(-3175 5375);
DISPLAY 0.872340 (-3175 5375);
PAINT GREEN (-3175 5375);
DISPLAY INVISIBLE (-3175 5375);
FORCEPROP 1 LAST COMMENT_BODY TRUE
J 2
(-2975 5400);
DISPLAY 0.872340 (-2975 5400);
PAINT GREEN (-2975 5400);
DISPLAY INVISIBLE (-2975 5400);
FORCEPROP 2 LAST PATH I78
J 0
(-2650 5550);
DISPLAY 0.680851 (-2650 5550);
DISPLAY INVISIBLE (-2650 5550);
FORCEADD OFFPAGE..1
R 2
(-2850 5400);
FORCEPROP 2 LAST $XR0 246 
J 0
(-2664 5400);
DISPLAY 0.638298 (-2664 5400);
PAINT MONO (-2664 5400);
FORCEPROP 2 LAST CDS_LIB standard
J 0
(-2850 5400);
DISPLAY INVISIBLE (-2850 5400);
FORCEPROP 1 LAST OFFPAGE TRUE
J 2
(-3175 5275);
DISPLAY 0.872340 (-3175 5275);
PAINT GREEN (-3175 5275);
DISPLAY INVISIBLE (-3175 5275);
FORCEPROP 1 LAST COMMENT_BODY TRUE
J 2
(-2975 5300);
DISPLAY 0.872340 (-2975 5300);
PAINT GREEN (-2975 5300);
DISPLAY INVISIBLE (-2975 5300);
FORCEPROP 2 LAST PATH I79
J 0
(-2650 5450);
DISPLAY 0.680851 (-2650 5450);
DISPLAY INVISIBLE (-2650 5450);
FORCEADD OFFPAGE..2
(-6050 2875);
FORCEPROP 2 LAST $XR0 246 
J 0
(-5861 2875);
DISPLAY 0.638298 (-5861 2875);
PAINT MONO (-5861 2875);
FORCEPROP 2 LAST CDS_LIB standard
J 0
(-6050 2875);
DISPLAY INVISIBLE (-6050 2875);
FORCEPROP 1 LAST OFFPAGE TRUE
J 0
(-5725 2750);
DISPLAY 0.872340 (-5725 2750);
DISPLAY INVISIBLE (-5725 2750);
FORCEPROP 1 LAST COMMENT_BODY TRUE
J 0
(-6095 2780);
DISPLAY 0.872340 (-6095 2780);
PAINT GREEN (-6095 2780);
DISPLAY INVISIBLE (-6095 2780);
FORCEPROP 2 LAST PATH I8
J 0
(-5850 2925);
DISPLAY 0.680851 (-5850 2925);
DISPLAY INVISIBLE (-5850 2925);
FORCEADD OFFPAGE..2
(-2225 1500);
FORCEPROP 2 LAST $XR0 246 
J 0
(-2036 1500);
DISPLAY 0.638298 (-2036 1500);
PAINT MONO (-2036 1500);
FORCEPROP 2 LAST CDS_LIB standard
J 0
(-2225 1500);
DISPLAY INVISIBLE (-2225 1500);
FORCEPROP 1 LAST OFFPAGE TRUE
J 0
(-1900 1375);
DISPLAY 0.872340 (-1900 1375);
PAINT GREEN (-1900 1375);
DISPLAY INVISIBLE (-1900 1375);
FORCEPROP 1 LAST COMMENT_BODY TRUE
J 0
(-2270 1405);
DISPLAY 0.872340 (-2270 1405);
PAINT PEACH (-2270 1405);
DISPLAY INVISIBLE (-2270 1405);
FORCEPROP 2 LAST PATH I80
J 0
(-2025 1550);
DISPLAY 0.680851 (-2025 1550);
DISPLAY INVISIBLE (-2025 1550);
FORCEADD OFFPAGE..2
(-2225 1600);
FORCEPROP 2 LAST $XR0 246 
J 0
(-2036 1600);
DISPLAY 0.638298 (-2036 1600);
PAINT MONO (-2036 1600);
FORCEPROP 2 LAST CDS_LIB standard
J 0
(-2225 1600);
DISPLAY INVISIBLE (-2225 1600);
FORCEPROP 1 LAST OFFPAGE TRUE
J 0
(-1900 1475);
DISPLAY 0.872340 (-1900 1475);
PAINT GREEN (-1900 1475);
DISPLAY INVISIBLE (-1900 1475);
FORCEPROP 1 LAST COMMENT_BODY TRUE
J 0
(-2270 1505);
DISPLAY 0.872340 (-2270 1505);
PAINT PEACH (-2270 1505);
DISPLAY INVISIBLE (-2270 1505);
FORCEPROP 2 LAST PATH I81
J 0
(-2025 1650);
DISPLAY 0.680851 (-2025 1650);
DISPLAY INVISIBLE (-2025 1650);
FORCEADD Q_RES..1
(-3525 3250);
FORCEPROP 1 LAST LOCATION R2982
J 0
(-3725 3250);
DISPLAY 0.510638 (-3725 3250);
FORCEPROP 0 LAST $SEC 1
J 0
(-3275 3275);
DISPLAY 0.680851 (-3275 3275);
PAINT MONO (-3275 3275);
DISPLAY INVISIBLE (-3275 3275);
FORCEPROP 0 LAST CDS_SEC 1
J 0
(-3275 3275);
DISPLAY 1.021277 (-3275 3275);
DISPLAY INVISIBLE (-3275 3275);
FORCEPROP 1 LASTPIN (-3625 3250) $PN 1
J 0
(-3613 3262);
DISPLAY 0.787234 (-3613 3262);
PAINT MONO (-3613 3262);
FORCEPROP 1 LASTPIN (-3425 3250) $PN 2
J 0
(-3463 3262);
DISPLAY 0.787234 (-3463 3262);
PAINT MONO (-3463 3262);
FORCEPROP 1 LAST MATERIAL CHIP
J 0
(-3275 3250);
DISPLAY 0.510638 (-3275 3250);
FORCEPROP 1 LAST TOLERANCE 5%
J 0
(-3350 3250);
DISPLAY 0.510638 (-3350 3250);
FORCEPROP 1 LAST VALUE 0
J 2
(-3375 3250);
DISPLAY 0.510638 (-3375 3250);
FORCEPROP 1 LAST WATTAGE 1/16W
J 2
(-3350 3325);
DISPLAY 0.404255 (-3350 3325);
DISPLAY INVISIBLE (-3350 3325);
FORCEPROP 1 LAST PACK_TYPE 0402LF
J 0
(-3275 3250);
DISPLAY 0.510638 (-3275 3250);
DISPLAY INVISIBLE (-3275 3250);
FORCEPROP 2 LAST CDS_LIB pure_quanta
J 0
(-3525 3250);
DISPLAY INVISIBLE (-3525 3250);
FORCEPROP 1 LAST PATH I82
J 0
(-3575 3400);
DISPLAY 0.978723 (-3575 3400);
PAINT WHITE (-3575 3400);
DISPLAY INVISIBLE (-3575 3400);
FORCEPROP 1 LAST PART_NUMBER CS00002JB13
J 0
(-3575 3300);
DISPLAY 0.404255 (-3575 3300);
DISPLAY INVISIBLE (-3575 3300);
FORCEADD PCA9539RPW..1
(-4400 4950);
FORCEPROP 1 LAST LOCATION U181
J 0
(-4647 5833);
DISPLAY 0.723404 (-4647 5833);
PAINT GREEN (-4647 5833);
FORCEPROP 2 LAST SEC 1
J 0
(-4625 5975);
DISPLAY 0.680851 (-4625 5975);
PAINT MONO (-4625 5975);
DISPLAY INVISIBLE (-4625 5975);
FORCEPROP 2 LASTPIN (-4000 4700) $PN 21
J 0
(-3990 4710);
DISPLAY 0.680851 (-3990 4710);
PAINT MONO (-3990 4710);
FORCEPROP 2 LASTPIN (-4800 5400) $PN 2
J 2
(-4810 5410);
DISPLAY 0.680851 (-4810 5410);
PAINT MONO (-4810 5410);
FORCEPROP 2 LASTPIN (-4800 5500) $PN 1
J 2
(-4810 5510);
DISPLAY 0.680851 (-4810 5510);
PAINT MONO (-4810 5510);
FORCEPROP 2 LASTPIN (-4800 5200) $PN 4
J 2
(-4810 5210);
DISPLAY 0.680851 (-4810 5210);
PAINT MONO (-4810 5210);
FORCEPROP 2 LASTPIN (-4800 5100) $PN 5
J 2
(-4810 5110);
DISPLAY 0.680851 (-4810 5110);
PAINT MONO (-4810 5110);
FORCEPROP 2 LASTPIN (-4800 5000) $PN 6
J 2
(-4810 5010);
DISPLAY 0.680851 (-4810 5010);
PAINT MONO (-4810 5010);
FORCEPROP 2 LASTPIN (-4800 4900) $PN 7
J 2
(-4810 4910);
DISPLAY 0.680851 (-4810 4910);
PAINT MONO (-4810 4910);
FORCEPROP 2 LASTPIN (-4800 4800) $PN 8
J 2
(-4810 4810);
DISPLAY 0.680851 (-4810 4810);
PAINT MONO (-4810 4810);
FORCEPROP 2 LASTPIN (-4800 4700) $PN 9
J 2
(-4810 4710);
DISPLAY 0.680851 (-4810 4710);
PAINT MONO (-4810 4710);
FORCEPROP 2 LASTPIN (-4800 4600) $PN 10
J 2
(-4810 4610);
DISPLAY 0.680851 (-4810 4610);
PAINT MONO (-4810 4610);
FORCEPROP 2 LASTPIN (-4800 4500) $PN 11
J 2
(-4810 4510);
DISPLAY 0.680851 (-4810 4510);
PAINT MONO (-4810 4510);
FORCEPROP 2 LASTPIN (-4000 5500) $PN 13
J 0
(-3990 5510);
DISPLAY 0.680851 (-3990 5510);
PAINT MONO (-3990 5510);
FORCEPROP 2 LASTPIN (-4000 5400) $PN 14
J 0
(-3990 5410);
DISPLAY 0.680851 (-3990 5410);
PAINT MONO (-3990 5410);
FORCEPROP 2 LASTPIN (-4000 5300) $PN 15
J 0
(-3990 5310);
DISPLAY 0.680851 (-3990 5310);
PAINT MONO (-3990 5310);
FORCEPROP 2 LASTPIN (-4000 5200) $PN 16
J 0
(-3990 5210);
DISPLAY 0.680851 (-3990 5210);
PAINT MONO (-3990 5210);
FORCEPROP 2 LASTPIN (-4000 5100) $PN 17
J 0
(-3990 5110);
DISPLAY 0.680851 (-3990 5110);
PAINT MONO (-3990 5110);
FORCEPROP 2 LASTPIN (-4000 5000) $PN 18
J 0
(-3990 5010);
DISPLAY 0.680851 (-3990 5010);
PAINT MONO (-3990 5010);
FORCEPROP 2 LASTPIN (-4000 4900) $PN 19
J 0
(-3990 4910);
DISPLAY 0.680851 (-3990 4910);
PAINT MONO (-3990 4910);
FORCEPROP 2 LASTPIN (-4000 4800) $PN 20
J 0
(-3990 4810);
DISPLAY 0.680851 (-3990 4810);
PAINT MONO (-3990 4810);
FORCEPROP 2 LASTPIN (-4800 5300) $PN 3
J 2
(-4810 5310);
DISPLAY 0.680851 (-4810 5310);
PAINT MONO (-4810 5310);
FORCEPROP 2 LASTPIN (-4000 4600) $PN 22
J 0
(-3990 4610);
DISPLAY 0.680851 (-3990 4610);
PAINT MONO (-3990 4610);
FORCEPROP 2 LASTPIN (-4000 4500) $PN 23
J 0
(-3990 4510);
DISPLAY 0.680851 (-3990 4510);
PAINT MONO (-3990 4510);
FORCEPROP 2 LASTPIN (-4000 4400) $PN 24
J 0
(-3990 4410);
DISPLAY 0.680851 (-3990 4410);
PAINT MONO (-3990 4410);
FORCEPROP 2 LASTPIN (-4800 4400) $PN 12
J 2
(-4810 4410);
DISPLAY 0.680851 (-4810 4410);
PAINT MONO (-4810 4410);
FORCEPROP 2 LAST VALUE PCA9539RPW
J 0
(-4625 5875);
DISPLAY 1.021277 (-4625 5875);
FORCEPROP 1 LAST MATERIAL IC
J 0
(-4647 5559);
DISPLAY 0.723404 (-4647 5559);
PAINT GREEN (-4647 5559);
FORCEPROP 2 LAST PART_TYPE SMLF
J 0
(-4625 5925);
DISPLAY 1.021277 (-4625 5925);
FORCEPROP 1 LAST CDS_LMAN_SYM_OUTLINE -250,600,250,-600
J 0
(-4400 4950);
DISPLAY 0.468085 (-4400 4950);
PAINT GREEN (-4400 4950);
DISPLAY INVISIBLE (-4400 4950);
FORCEPROP 1 LAST NEEDS_NO_SIZE TRUE
J 0
(-4400 4950);
DISPLAY 0.723404 (-4400 4950);
PAINT GREEN (-4400 4950);
DISPLAY INVISIBLE (-4400 4950);
FORCEPROP 2 LAST CDS_LIB pure_quanta
J 0
(-4400 4950);
DISPLAY INVISIBLE (-4400 4950);
FORCEPROP 2 LAST SEC_TYPE 
J 0
(-4625 5975);
DISPLAY 1.021277 (-4625 5975);
DISPLAY INVISIBLE (-4625 5975);
FORCEPROP 1 LAST PATH I83
J 0
(-4400 4950);
DISPLAY 0.723404 (-4400 4950);
PAINT GREEN (-4400 4950);
DISPLAY INVISIBLE (-4400 4950);
FORCEPROP 1 LAST PART_NUMBER AL009539K07
J 0
(-4647 5686);
DISPLAY 0.723404 (-4647 5686);
PAINT GREEN (-4647 5686);
DISPLAY INVISIBLE (-4647 5686);
FORCEADD OFFPAGE..2
(-6050 2775);
FORCEPROP 2 LAST $XR0 246 
J 0
(-5861 2775);
DISPLAY 0.638298 (-5861 2775);
PAINT MONO (-5861 2775);
FORCEPROP 2 LAST CDS_LIB standard
J 0
(-6050 2775);
DISPLAY INVISIBLE (-6050 2775);
FORCEPROP 1 LAST OFFPAGE TRUE
J 0
(-5725 2650);
DISPLAY 0.872340 (-5725 2650);
DISPLAY INVISIBLE (-5725 2650);
FORCEPROP 1 LAST COMMENT_BODY TRUE
J 0
(-6095 2680);
DISPLAY 0.872340 (-6095 2680);
PAINT GREEN (-6095 2680);
DISPLAY INVISIBLE (-6095 2680);
FORCEPROP 2 LAST PATH I9
J 0
(-5850 2825);
DISPLAY 0.680851 (-5850 2825);
DISPLAY INVISIBLE (-5850 2825);
FORCEADD DNS..2
(-6920 3120);
PAINT RED (-6920 3120);
FORCEPROP 2 LAST CDS_LIB mstr_misc
J 0
(-6920 3120);
PAINT MONO (-6920 3120);
DISPLAY INVISIBLE (-6920 3120);
FORCEPROP 1 LAST COMMENT_BODY TRUE
J 0
(-6920 3120);
DISPLAY INVISIBLE (-6920 3120);
FORCEADD DNS..2
(-7175 3100);
PAINT RED (-7175 3100);
FORCEPROP 2 LAST CDS_LIB mstr_misc
J 0
(-7175 3100);
PAINT MONO (-7175 3100);
DISPLAY INVISIBLE (-7175 3100);
FORCEPROP 1 LAST COMMENT_BODY TRUE
J 0
(-7175 3100);
DISPLAY INVISIBLE (-7175 3100);
FORCEADD QUANTA_TITLE_BLOCK_C..1
(0 0);
FORCEPROP 0 LAST CDS_CON_LAST_MODIFIED Thu Sep 14 16:12:33 2023
J 0
(-1885 15);
DISPLAY INVISIBLE (-1885 15);
FORCEPROP 1 LAST CUSTOM_TXT_CDS <CON_LAST_MODIFIED>
J 0
(-1885 15);
DISPLAY 0.978723 (-1885 15);
FORCEPROP 2 LAST CUSTOM_TXT_CDS <XR_PAGE_TITLE>
J 0
(-7890 5250);
DISPLAY 0.638298 (-7890 5250);
PAINT PINK (-7890 5250);
DISPLAY INVISIBLE (-7890 5250);
FORCEPROP 1 LAST CUSTOM_TXT_CDS <NAME_2>
J 0
(-3175 50);
FORCEPROP 1 LAST CUSTOM_TXT_CDS <NAME_1>
J 0
(-3175 175);
FORCEPROP 1 LAST CUSTOM_TXT_CDS <Q_NUMBER>
J 0
(-1403 103);
DISPLAY 1.212766 (-1403 103);
FORCEPROP 1 LAST CUSTOM_TXT_CDS <Q_PROJ>
J 0
(-2382 102);
DISPLAY 1.212766 (-2382 102);
FORCEPROP 1 LAST CUSTOM_TXT_CDS <Q_REV>
J 0
(-184 103);
DISPLAY 1.212766 (-184 103);
FORCEPROP 1 LAST CUSTOM_TXT_CDS <CON_PAGE_NUM> OF <CON_TOTAL_PAGES>
J 0
(-446 18);
DISPLAY 0.978723 (-446 18);
FORCEPROP 1 LAST Q_TITLE BMC - PCA9539
J 0
(-9366 26);
DISPLAY 2.446809 (-9366 26);
PAINT GREEN (-9366 26);
FORCEPROP 2 LAST PAGE_BORDER TRUE
J 0
(-7890 5250);
DISPLAY 0.638298 (-7890 5250);
PAINT PINK (-7890 5250);
DISPLAY INVISIBLE (-7890 5250);
FORCEPROP 1 LAST CDS_LMAN_SYM_OUTLINE -9475,6775,100,-125
J 0
(0 0);
DISPLAY 0.468085 (0 0);
PAINT GREEN (0 0);
DISPLAY INVISIBLE (0 0);
FORCEPROP 2 LAST CDS_LIB pure_quanta
J 0
(0 0);
DISPLAY INVISIBLE (0 0);
FORCEPROP 2 LAST CDS_XR_PAGE_TITLE CR-246 : @T6G_MB_LIB.T6G(SCH_1):PAGE246
J 0
(-7890 5250);
DISPLAY 0.638298 (-7890 5250);
PAINT PINK (-7890 5250);
DISPLAY INVISIBLE (-7890 5250);
FORCEPROP 1 LAST Q_DEPT BU9
J 1
(-3763 49);
DISPLAY 1.957447 (-3763 49);
PAINT GREEN (-3763 49);
DISPLAY INVISIBLE (-3763 49);
FORCEPROP 1 LAST COMMENT_BODY TRUE
J 0
(12 -13);
DISPLAY 0.978723 (12 -13);
PAINT GREEN (12 -13);
DISPLAY INVISIBLE (12 -13);
FORCEADD DNS..2
(-6575 5625);
PAINT RED (-6575 5625);
FORCEPROP 2 LAST CDS_LIB mstr_misc
J 0
(-6575 5625);
DISPLAY INVISIBLE (-6575 5625);
FORCEPROP 1 LAST COMMENT_BODY TRUE
J 0
(-6575 5625);
DISPLAY INVISIBLE (-6575 5625);
WIRE 16 -1 (-7175 2425)(-7175 2350);
WIRE 16 -1 (-4950 4400)(-4800 4400);
WIRE 16 -1 (-4950 4400)(-4950 4225);
WIRE 16 -1 (-6575 5875)(-6575 5750);
WIRE 16 -1 (-5600 5975)(-5600 5900);
WIRE 16 -1 (-6925 2425)(-6925 2350);
WIRE 16 -1 (-3275 3800)(-3275 3725);
WIRE 16 -1 (-3425 2250)(-2300 2250);
FORCEPROP 0 LAST CDS_PHYS_NET_NAME GPU_PEX_STRAP0_R
J 0
(-3110 2290);
PAINT MONO (-3110 2290);
DISPLAY INVISIBLE (-3110 2290);
FORCEPROP 2 LAST SIG_NAME GPU_PEX_STRAP0_R
J 0
(-3085 2260);
DISPLAY 0.638298 (-3085 2260);
PAINT WHITE (-3085 2260);
WIRE 16 -1 (-3425 2850)(-2300 2850);
FORCEPROP 0 LAST CDS_PHYS_NET_NAME GPU_BASE_ID1_R
J 0
(-3110 2890);
PAINT MONO (-3110 2890);
DISPLAY INVISIBLE (-3110 2890);
FORCEPROP 2 LAST SIG_NAME GPU_BASE_ID1_R
J 0
(-3110 2860);
DISPLAY 0.638298 (-3110 2860);
PAINT WHITE (-3110 2860);
WIRE 16 2175 (-5150 1250)(-1900 1250);
WIRE 16 2175 (-5150 1975)(-5150 1250);
WIRE 16 2175 (-1900 1975)(-1900 1250);
WIRE 16 2175 (-5150 1975)(-1900 1975);
WIRE 16 -1 (-3425 1825)(-2275 1825);
FORCEPROP 2 LAST SIG_NAME GPU_PRSNT_N_ISO_R1
J 0
(-3125 1835);
DISPLAY 0.680851 (-3125 1835);
WIRE 16 -1 (-3425 2450)(-2300 2450);
FORCEPROP 0 LAST CDS_PHYS_NET_NAME GPU_PEX_STRAP1_R
J 0
(-3110 2490);
PAINT MONO (-3110 2490);
DISPLAY INVISIBLE (-3110 2490);
FORCEPROP 2 LAST SIG_NAME GPU_PEX_STRAP1_R
J 0
(-3085 2460);
DISPLAY 0.638298 (-3085 2460);
PAINT WHITE (-3085 2460);
WIRE 16 -1 (-3425 3050)(-2300 3050);
FORCEPROP 0 LAST CDS_PHYS_NET_NAME SMB_IOEXP_3V3AUX_SDA_R1
J 0
(-3110 3090);
PAINT MONO (-3110 3090);
DISPLAY INVISIBLE (-3110 3090);
FORCEPROP 2 LAST SIG_NAME SMB_IOEXP_3V3AUX_SDA_R1
J 0
(-3110 3060);
DISPLAY 0.638298 (-3110 3060);
PAINT WHITE (-3110 3060);
WIRE 16 -1 (-3425 3250)(-2300 3250);
FORCEPROP 0 LAST CDS_PHYS_NET_NAME SMB_IOEXP_3V3AUX_SCL_R1
J 0
(-3110 3290);
PAINT MONO (-3110 3290);
DISPLAY INVISIBLE (-3110 3290);
FORCEPROP 2 LAST SIG_NAME SMB_IOEXP_3V3AUX_SCL_R1
J 0
(-3110 3260);
DISPLAY 0.638298 (-3110 3260);
PAINT WHITE (-3110 3260);
WIRE 16 -1 (-5925 5200)(-4800 5200);
FORCEPROP 0 LAST CDS_PHYS_NET_NAME RST_USB_HUB_N
J 0
(-5585 5242);
PAINT MONO (-5585 5242);
DISPLAY INVISIBLE (-5585 5242);
FORCEPROP 2 LAST SIG_NAME RST_USB_HUB_N
J 0
(-5850 5210);
DISPLAY 0.553191 (-5850 5210);
PAINT WHITE (-5850 5210);
FORCEPROP 0 LAST $PHYS_NET_NAME RST_PCIE_M2_N
J 0
(-5585 5289);
PAINT MONO (-5585 5289);
DISPLAY INVISIBLE (-5585 5289);
WIRE 16 -1 (-5925 5100)(-4800 5100);
FORCEPROP 0 LAST CDS_PHYS_NET_NAME RST_SWB_BIC_N
J 0
(-4985 5142);
PAINT MONO (-4985 5142);
DISPLAY INVISIBLE (-4985 5142);
FORCEPROP 2 LAST SIG_NAME RST_SWB_BIC_N
J 0
(-5850 5110);
DISPLAY 0.553191 (-5850 5110);
PAINT WHITE (-5850 5110);
FORCEPROP 0 LAST $PHYS_NET_NAME RST_PCIE_M2_N
J 0
(-4985 5189);
PAINT MONO (-4985 5189);
DISPLAY INVISIBLE (-4985 5189);
WIRE 16 -1 (-5925 5000)(-4800 5000);
FORCEPROP 0 LAST CDS_PHYS_NET_NAME TP_TCA9539_0_P0_2
J 0
(-4985 5042);
PAINT MONO (-4985 5042);
DISPLAY INVISIBLE (-4985 5042);
FORCEPROP 2 LAST SIG_NAME TP_TCA9539_0_P0_2
J 0
(-5850 5010);
DISPLAY 0.553191 (-5850 5010);
PAINT WHITE (-5850 5010);
FORCEPROP 2 LASTPROP $XRERR UNIQUE?
J 0
(-6165 5000);
DISPLAY 0.638298 (-6165 5000);
PAINT MONO (-6165 5000);
DISPLAY INVISIBLE (-6165 5000);
FORCEPROP 0 LAST $PHYS_NET_NAME RST_PCIE_M2_N
J 0
(-4985 5089);
PAINT MONO (-4985 5089);
DISPLAY INVISIBLE (-4985 5089);
WIRE 16 -1 (-5925 4900)(-4800 4900);
FORCEPROP 0 LAST CDS_PHYS_NET_NAME TP_TCA9539_0_P0_3
J 0
(-4985 4942);
PAINT MONO (-4985 4942);
DISPLAY INVISIBLE (-4985 4942);
FORCEPROP 2 LAST SIG_NAME TP_TCA9539_0_P0_3
J 0
(-5850 4910);
DISPLAY 0.553191 (-5850 4910);
PAINT WHITE (-5850 4910);
FORCEPROP 2 LASTPROP $XRERR UNIQUE?
J 0
(-6165 4900);
DISPLAY 0.638298 (-6165 4900);
PAINT MONO (-6165 4900);
DISPLAY INVISIBLE (-6165 4900);
FORCEPROP 0 LAST $PHYS_NET_NAME RST_PCIE_M2_N
J 0
(-4985 4989);
PAINT MONO (-4985 4989);
DISPLAY INVISIBLE (-4985 4989);
WIRE 16 -1 (-5925 4600)(-4800 4600);
FORCEPROP 0 LAST SIG_NAME PRSNT_CABLE_GPU_B3_ISO_R1_N
J 0
(-5850 4610);
DISPLAY 0.680851 (-5850 4610);
PAINT SKYBLUE (-5850 4610);
WIRE 16 -1 (-4000 4900)(-2900 4900);
FORCEPROP 0 LAST SIG_NAME PRSNT_CABLE_GPU_A1_ISO_R1_N
J 0
(-3900 4910);
DISPLAY 0.680851 (-3900 4910);
PAINT SKYBLUE (-3900 4910);
WIRE 16 -1 (-4000 5000)(-2900 5000);
FORCEPROP 0 LAST CDS_PHYS_NET_NAME GPU_PEX_STRAP1_R
J 0
(-3085 5042);
PAINT MONO (-3085 5042);
DISPLAY INVISIBLE (-3085 5042);
FORCEPROP 2 LAST SIG_NAME GPU_PEX_STRAP1_R
J 0
(-3900 5010);
DISPLAY 0.553191 (-3900 5010);
PAINT WHITE (-3900 5010);
FORCEPROP 0 LAST $PHYS_NET_NAME RST_PCIE_M2_N
J 0
(-3085 5089);
PAINT MONO (-3085 5089);
DISPLAY INVISIBLE (-3085 5089);
WIRE 16 -1 (-4000 5100)(-2900 5100);
FORCEPROP 0 LAST CDS_PHYS_NET_NAME GPU_PEX_STRAP0_R
J 0
(-3710 5142);
PAINT MONO (-3710 5142);
DISPLAY INVISIBLE (-3710 5142);
FORCEPROP 2 LAST SIG_NAME GPU_PEX_STRAP0_R
J 0
(-3900 5110);
DISPLAY 0.553191 (-3900 5110);
PAINT WHITE (-3900 5110);
FORCEPROP 0 LAST $PHYS_NET_NAME RST_PCIE_M2_N
J 0
(-3710 5189);
PAINT MONO (-3710 5189);
DISPLAY INVISIBLE (-3710 5189);
WIRE 16 -1 (-4000 5200)(-2900 5200);
FORCEPROP 0 LAST CDS_PHYS_NET_NAME GPU_BASE_ID1_R
J 0
(-3085 5242);
PAINT MONO (-3085 5242);
DISPLAY INVISIBLE (-3085 5242);
FORCEPROP 2 LAST SIG_NAME GPU_BASE_ID1_R
J 0
(-3900 5210);
DISPLAY 0.553191 (-3900 5210);
PAINT WHITE (-3900 5210);
FORCEPROP 0 LAST $PHYS_NET_NAME RST_PCIE_M2_N
J 0
(-3085 5289);
PAINT MONO (-3085 5289);
DISPLAY INVISIBLE (-3085 5289);
WIRE 16 -1 (-4000 5300)(-2900 5300);
FORCEPROP 0 LAST CDS_PHYS_NET_NAME GPU_BASE_ID0_R
J 0
(-3710 5342);
PAINT MONO (-3710 5342);
DISPLAY INVISIBLE (-3710 5342);
FORCEPROP 2 LAST SIG_NAME GPU_BASE_ID0_R
J 0
(-3900 5310);
DISPLAY 0.553191 (-3900 5310);
PAINT WHITE (-3900 5310);
FORCEPROP 0 LAST $PHYS_NET_NAME RST_PCIE_M2_N
J 0
(-3710 5389);
PAINT MONO (-3710 5389);
DISPLAY INVISIBLE (-3710 5389);
WIRE 16 -1 (-4000 5400)(-2900 5400);
FORCEPROP 0 LAST SIG_NAME PRSNT_CABLE_SWB_B1_ISO_R_N
J 0
(-3900 5410);
DISPLAY 0.680851 (-3900 5410);
PAINT SKYBLUE (-3900 5410);
WIRE 16 -1 (-4000 5500)(-2900 5500);
FORCEPROP 0 LAST SIG_NAME PRSNT_CABLE_GPU_A2_ISO_R1_N
J 0
(-3900 5510);
DISPLAY 0.680851 (-3900 5510);
PAINT SKYBLUE (-3900 5510);
WIRE 16 -1 (-4000 4500)(-2900 4500);
FORCEPROP 0 LAST CDS_PHYS_NET_NAME SMB_IOEXP_3V3AUX_SDA_R1
J 0
(-3310 4542);
PAINT MONO (-3310 4542);
DISPLAY INVISIBLE (-3310 4542);
FORCEPROP 2 LAST SIG_NAME SMB_IOEXP_3V3AUX_SDA_R1
J 0
(-3900 4510);
DISPLAY 0.553191 (-3900 4510);
PAINT WHITE (-3900 4510);
WIRE 16 -1 (-4000 4600)(-2900 4600);
FORCEPROP 0 LAST CDS_PHYS_NET_NAME SMB_IOEXP_3V3AUX_SCL_R1
J 0
(-3310 4642);
PAINT MONO (-3310 4642);
DISPLAY INVISIBLE (-3310 4642);
FORCEPROP 2 LAST SIG_NAME SMB_IOEXP_3V3AUX_SCL_R1
J 0
(-3900 4610);
DISPLAY 0.553191 (-3900 4610);
PAINT WHITE (-3900 4610);
WIRE 16 -1 (-4000 4700)(-2900 4700);
FORCEPROP 0 LAST CDS_PHYS_NET_NAME TCA9539_0_ADD0
J 0
(-3085 4742);
PAINT MONO (-3085 4742);
DISPLAY INVISIBLE (-3085 4742);
FORCEPROP 2 LAST SIG_NAME TCA9539_0_ADD0
J 0
(-3900 4710);
DISPLAY 0.553191 (-3900 4710);
PAINT WHITE (-3900 4710);
FORCEPROP 0 LAST $PHYS_NET_NAME RST_PCIE_M2_N
J 0
(-3085 4789);
PAINT MONO (-3085 4789);
DISPLAY INVISIBLE (-3085 4789);
WIRE 16 -1 (-4000 4800)(-2900 4800);
FORCEPROP 0 LAST SIG_NAME PRSNT_CABLE_GPU_A3_ISO_R_N
J 0
(-3900 4810);
DISPLAY 0.680851 (-3900 4810);
PAINT SKYBLUE (-3900 4810);
WIRE 16 -1 (-4000 4400)(-3850 4400);
WIRE 16 -1 (-3850 4400)(-3850 4075);
FORCEPROP 0 LAST VOLTAGE 3.3
J 0
(-3850 4237);
DISPLAY INVISIBLE (-3850 4237);
WIRE 16 -1 (-3850 4075)(-3275 4075);
WIRE 16 -1 (-3275 4075)(-3275 4125);
WIRE 16 -1 (-3275 4000)(-3275 4075);
WIRE 16 -1 (-3425 3475)(-2300 3475);
FORCEPROP 0 LAST CDS_PHYS_NET_NAME RST_SWB_BIC_R_N
J 0
(-3110 3515);
PAINT MONO (-3110 3515);
DISPLAY INVISIBLE (-3110 3515);
FORCEPROP 2 LAST SIG_NAME RST_SWB_BIC_R_N
J 0
(-3110 3485);
DISPLAY 0.638298 (-3110 3485);
PAINT WHITE (-3110 3485);
WIRE 16 -1 (-3425 2650)(-2300 2650);
FORCEPROP 0 LAST CDS_PHYS_NET_NAME GPU_BASE_ID0_R
J 0
(-3110 2690);
PAINT MONO (-3110 2690);
DISPLAY INVISIBLE (-3110 2690);
FORCEPROP 2 LAST SIG_NAME GPU_BASE_ID0_R
J 0
(-3110 2660);
DISPLAY 0.638298 (-3110 2660);
PAINT WHITE (-3110 2660);
WIRE 16 -1 (-3425 875)(-2275 875);
FORCEPROP 0 LAST SIG_NAME PRSNT_CABLE_SWB_B2_ISO_R_N
J 0
(-3125 885);
DISPLAY 0.680851 (-3125 885);
PAINT SKYBLUE (-3125 885);
WIRE 16 -1 (-3425 1500)(-2275 1500);
FORCEPROP 0 LAST SIG_NAME PRSNT_CABLE_GPU_A2_ISO_R1_N
J 0
(-3125 1510);
DISPLAY 0.680851 (-3125 1510);
PAINT SKYBLUE (-3125 1510);
WIRE 16 -1 (-3425 1600)(-2275 1600);
FORCEPROP 0 LAST SIG_NAME PRSNT_CABLE_GPU_A3_ISO_R_N
J 0
(-3125 1610);
DISPLAY 0.680851 (-3125 1610);
PAINT SKYBLUE (-3125 1610);
WIRE 16 -1 (-3425 1700)(-2275 1700);
FORCEPROP 0 LAST SIG_NAME PRSNT_CABLE_GPU_B3_ISO_R1_N
J 0
(-3125 1710);
DISPLAY 0.680851 (-3125 1710);
PAINT SKYBLUE (-3125 1710);
WIRE 16 -1 (-3425 1075)(-2275 1075);
FORCEPROP 2 LAST SIG_NAME PRSNT_SWB_ISO_R1_N
J 0
(-3125 1085);
DISPLAY 0.680851 (-3125 1085);
WIRE 16 -1 (-3425 975)(-2275 975);
FORCEPROP 0 LAST SIG_NAME PRSNT_CABLE_SWB_B1_ISO_R_N
J 0
(-3125 985);
DISPLAY 0.680851 (-3125 985);
PAINT SKYBLUE (-3125 985);
WIRE 16 -1 (-3425 1400)(-2275 1400);
FORCEPROP 0 LAST SIG_NAME PRSNT_CABLE_GPU_A1_ISO_R1_N
J 0
(-3125 1410);
DISPLAY 0.680851 (-3125 1410);
PAINT SKYBLUE (-3125 1410);
WIRE 16 -1 (-4700 2850)(-3625 2850);
FORCEPROP 0 LAST CDS_PHYS_NET_NAME GPU_BASE_ID1
J 0
(-4675 2892);
PAINT MONO (-4675 2892);
DISPLAY INVISIBLE (-4675 2892);
FORCEPROP 0 LAST SIG_NAME GPU_BASE_ID1
J 0
(-4600 2860);
DISPLAY 0.680851 (-4600 2860);
PAINT WHITE (-4600 2860);
WIRE 16 -1 (-4700 3050)(-3625 3050);
FORCEPROP 0 LAST CDS_PHYS_NET_NAME SMB_IOEXP_3V3AUX_SDA
J 0
(-4675 3092);
PAINT MONO (-4675 3092);
DISPLAY INVISIBLE (-4675 3092);
FORCEPROP 0 LAST SIG_NAME SMB_IOEXP_3V3AUX_SDA
J 0
(-4600 3060);
DISPLAY 0.680851 (-4600 3060);
PAINT WHITE (-4600 3060);
WIRE 16 -1 (-4700 2650)(-3625 2650);
FORCEPROP 0 LAST CDS_PHYS_NET_NAME GPU_BASE_ID0
J 0
(-4675 2692);
PAINT MONO (-4675 2692);
DISPLAY INVISIBLE (-4675 2692);
FORCEPROP 0 LAST SIG_NAME GPU_BASE_ID0
J 0
(-4600 2660);
DISPLAY 0.680851 (-4600 2660);
PAINT WHITE (-4600 2660);
WIRE 16 -1 (-4700 3475)(-3625 3475);
FORCEPROP 0 LAST CDS_PHYS_NET_NAME RST_SWB_BIC_N
J 0
(-4675 3517);
PAINT MONO (-4675 3517);
DISPLAY INVISIBLE (-4675 3517);
FORCEPROP 0 LAST SIG_NAME RST_SWB_BIC_N
J 0
(-4600 3485);
DISPLAY 0.680851 (-4600 3485);
PAINT WHITE (-4600 3485);
WIRE 16 -1 (-4700 3250)(-3625 3250);
FORCEPROP 0 LAST CDS_PHYS_NET_NAME SMB_IOEXP_3V3AUX_SCL
J 0
(-4675 3292);
PAINT MONO (-4675 3292);
DISPLAY INVISIBLE (-4675 3292);
FORCEPROP 0 LAST SIG_NAME SMB_IOEXP_3V3AUX_SCL
J 0
(-4600 3260);
DISPLAY 0.680851 (-4600 3260);
PAINT WHITE (-4600 3260);
WIRE 16 -1 (-4700 2450)(-3625 2450);
FORCEPROP 0 LAST CDS_PHYS_NET_NAME GPU_PEX_STRAP1
J 0
(-4675 2492);
PAINT MONO (-4675 2492);
DISPLAY INVISIBLE (-4675 2492);
FORCEPROP 0 LAST SIG_NAME GPU_PEX_STRAP1
J 0
(-4600 2460);
DISPLAY 0.680851 (-4600 2460);
PAINT WHITE (-4600 2460);
WIRE 16 -1 (-4700 2250)(-3625 2250);
FORCEPROP 0 LAST CDS_PHYS_NET_NAME GPU_PEX_STRAP0
J 0
(-4675 2292);
PAINT MONO (-4675 2292);
DISPLAY INVISIBLE (-4675 2292);
FORCEPROP 0 LAST SIG_NAME GPU_PEX_STRAP0
J 0
(-4600 2260);
DISPLAY 0.680851 (-4600 2260);
PAINT WHITE (-4600 2260);
WIRE 16 -1 (-4700 975)(-3625 975);
FORCEPROP 2 LAST SIG_NAME PRSNT_CABLE_SWB_B1_ISO_N
J 0
(-4525 985);
DISPLAY 0.680851 (-4525 985);
PAINT SKYBLUE (-4525 985);
WIRE 16 -1 (-3625 1825)(-4700 1825);
FORCEPROP 2 LAST SIG_NAME GPU_PRSNT_N_ISO
J 0
(-4525 1835);
DISPLAY 0.680851 (-4525 1835);
WIRE 16 -1 (-4700 1700)(-3625 1700);
FORCEPROP 2 LAST SIG_NAME PRSNT_CABLE_GPU_B3_ISO_N
J 0
(-4525 1710);
DISPLAY 0.680851 (-4525 1710);
PAINT SKYBLUE (-4525 1710);
WIRE 16 -1 (-4700 1600)(-3625 1600);
FORCEPROP 2 LAST SIG_NAME PRSNT_CABLE_GPU_A3_ISO_N
J 0
(-4525 1610);
DISPLAY 0.680851 (-4525 1610);
PAINT SKYBLUE (-4525 1610);
WIRE 16 -1 (-4700 1400)(-3625 1400);
FORCEPROP 2 LAST SIG_NAME PRSNT_CABLE_GPU_A1_ISO_N
J 0
(-4525 1410);
DISPLAY 0.680851 (-4525 1410);
PAINT SKYBLUE (-4525 1410);
WIRE 16 -1 (-3625 1075)(-4700 1075);
FORCEPROP 2 LAST SIG_NAME PRSNT_SWB_ISO_N
J 0
(-4525 1085);
DISPLAY 0.680851 (-4525 1085);
WIRE 16 2175 (-5150 750)(-1900 750);
WIRE 16 2175 (-5150 1225)(-5150 750);
WIRE 16 2175 (-1900 1225)(-1900 750);
WIRE 16 2175 (-5150 1225)(-1900 1225);
WIRE 16 -1 (-4700 875)(-3625 875);
FORCEPROP 2 LAST SIG_NAME PRSNT_CABLE_SWB_B2_ISO_N
J 0
(-4525 885);
DISPLAY 0.680851 (-4525 885);
PAINT SKYBLUE (-4525 885);
WIRE 16 -1 (-4700 1500)(-3625 1500);
FORCEPROP 2 LAST SIG_NAME PRSNT_CABLE_GPU_A2_ISO_N
J 0
(-4525 1510);
DISPLAY 0.680851 (-4525 1510);
PAINT SKYBLUE (-4525 1510);
WIRE 16 -1 (-5925 4500)(-4800 4500);
FORCEPROP 0 LAST SIG_NAME PRSNT_CABLE_SWB_B2_ISO_R_N
J 0
(-5850 4510);
DISPLAY 0.680851 (-5850 4510);
PAINT SKYBLUE (-5850 4510);
WIRE 16 -1 (-5925 5400)(-4800 5400);
FORCEPROP 0 LAST CDS_PHYS_NET_NAME TCA9539_0_ADD1
J 0
(-4985 5442);
PAINT MONO (-4985 5442);
DISPLAY INVISIBLE (-4985 5442);
FORCEPROP 2 LAST SIG_NAME TCA9539_0_ADD1
J 0
(-5850 5410);
DISPLAY 0.553191 (-5850 5410);
PAINT WHITE (-5850 5410);
FORCEPROP 0 LAST $PHYS_NET_NAME RST_PCIE_M2_N
J 0
(-4985 5489);
PAINT MONO (-4985 5489);
DISPLAY INVISIBLE (-4985 5489);
WIRE 16 -1 (-5925 4700)(-4800 4700);
FORCEPROP 2 LAST SIG_NAME GPU_PRSNT_N_ISO_R1
J 0
(-5850 4710);
DISPLAY 0.680851 (-5850 4710);
WIRE 16 -1 (-4800 4800)(-5925 4800);
FORCEPROP 2 LAST SIG_NAME PRSNT_SWB_ISO_R1_N
J 0
(-5850 4810);
DISPLAY 0.680851 (-5850 4810);
WIRE 16 -1 (-4800 5500)(-5600 5500);
FORCEPROP 2 LAST SIG_NAME PU_U181_INT
J 0
(-5435 5510);
DISPLAY 0.510638 (-5435 5510);
PAINT WHITE (-5435 5510);
FORCEPROP 2 LASTPROP $XRERR UNIQUE?
J 0
(-5675 5510);
DISPLAY 0.638298 (-5675 5510);
PAINT MONO (-5675 5510);
DISPLAY INVISIBLE (-5675 5510);
WIRE 16 -1 (-5600 5500)(-5600 5700);
WIRE 16 -1 (-4800 5300)(-6175 5300);
FORCEPROP 0 LAST CDS_PHYS_NET_NAME PU_RST_SMB_U181_N
J 0
(-6135 5348);
PAINT MONO (-6135 5348);
DISPLAY INVISIBLE (-6135 5348);
FORCEPROP 2 LAST SIG_NAME PU_RST_SMB_U181_N
J 0
(-5850 5310);
DISPLAY 0.510638 (-5850 5310);
PAINT WHITE (-5850 5310);
FORCEPROP 2 LASTPROP $XRERR UNIQUE?
J 0
(-6090 5310);
DISPLAY 0.638298 (-6090 5310);
PAINT MONO (-6090 5310);
DISPLAY INVISIBLE (-6090 5310);
WIRE 16 -1 (-6575 5550)(-6575 5300);
WIRE 16 -1 (-6375 5300)(-6575 5300);
WIRE 16 -1 (-7150 5300)(-6575 5300);
FORCEPROP 0 LAST CDS_PHYS_NET_NAME RST_SMB_SWITCH_N
J 0
(-7110 5348);
PAINT MONO (-7110 5348);
DISPLAY INVISIBLE (-7110 5348);
FORCEPROP 2 LAST SIG_NAME RST_SMB_SWITCH_N
J 0
(-7035 5310);
DISPLAY 0.510638 (-7035 5310);
PAINT WHITE (-7035 5310);
WIRE 16 -1 (-6925 2875)(-6100 2875);
FORCEPROP 0 LAST CDS_PHYS_NET_NAME TCA9539_0_ADD0
J 0
(-6485 2917);
PAINT MONO (-6485 2917);
DISPLAY INVISIBLE (-6485 2917);
FORCEPROP 2 LAST SIG_NAME TCA9539_0_ADD0
J 0
(-6710 2885);
DISPLAY 0.553191 (-6710 2885);
PAINT WHITE (-6710 2885);
WIRE 16 -1 (-6925 3025)(-6925 2875);
WIRE 16 -1 (-6925 2875)(-6925 2625);
WIRE 16 -1 (-6925 3225)(-6925 3400);
WIRE 16 -1 (-6925 3400)(-7175 3400);
WIRE 16 -1 (-7175 3475)(-7175 3400);
WIRE 16 -1 (-7175 3225)(-7175 3400);
WIRE 16 -1 (-6100 2775)(-7175 2775);
FORCEPROP 0 LAST CDS_PHYS_NET_NAME TCA9539_0_ADD1
J 0
(-6485 2817);
PAINT MONO (-6485 2817);
DISPLAY INVISIBLE (-6485 2817);
FORCEPROP 2 LAST SIG_NAME TCA9539_0_ADD1
J 0
(-6710 2785);
DISPLAY 0.553191 (-6710 2785);
PAINT WHITE (-6710 2785);
WIRE 16 -1 (-7175 3025)(-7175 2775);
WIRE 16 -1 (-7175 2775)(-7175 2625);
DOT 1 (-3275 4075);
DOT 1 (-6575 5300);
DOT 1 (-6925 2875);
DOT 1 (-7175 3400);
DOT 1 (-7175 2775);
FORCENOTE
PCA9539 ADDR: 0XE8 (8-BIT) / 0X74 (7-BIT)
(-7625 3875) 0;
DISPLAY LEFT (-7625 3875);
DISPLAY 1.595745 (-7625 3875);
PAINT SKYBLUE (-7625 3875);
QUIT
